G04 ================== begin FILE IDENTIFICATION RECORD ==================*
G04 Layout Name:  15750-1.brd*
G04 Film Name:    TSILK*
G04 File Format:  Gerber RS274X*
G04 File Origin:  Cadence Allegro 16.5-S056*
G04 Origin Date:  Fri Dec 30 13:21:32 2016*
G04 *
G04 Layer:  VIA CLASS/FILMMASKTOP*
G04 Layer:  REF DES/ASSEMBLY_TOP*
G04 Layer:  PACKAGE GEOMETRY/SILKSCREEN_TOP*
G04 Layer:  DRAWING FORMAT/LAYER_PCB_STORY*
G04 Layer:  DRAWING FORMAT/LAYER_SILK_T*
G04 Layer:  BOARD GEOMETRY/SILKSCREEN_TOP*
G04 *
G04 Offset:    (0.00 0.00)*
G04 Mirror:    No*
G04 Mode:      Positive*
G04 Rotation:  0*
G04 FullContactRelief:  No*
G04 UndefLineWidth:     6.00*
G04 ================== end FILE IDENTIFICATION RECORD ====================*
%FSLAX35Y35*MOIN*%
%IR0*IPPOS*OFA0.00000B0.00000*MIA0B0*SFA1.00000B1.00000*%
%ADD10C,.01*%
%ADD11C,.02*%
%ADD12C,.012*%
%ADD13C,.013*%
%ADD14C,.022*%
%ADD15C,.015*%
%ADD16C,.016*%
%ADD17C,.002*%
%ADD18C,.005*%
%ADD19C,.006*%
%ADD20C,.008*%
G75*
%LPD*%
G75*
G36*
G01X77900Y325589D02*
X80900D01*
Y322589D01*
X77900Y325589D01*
G37*
G36*
G01X106100Y338489D02*
X123900D01*
Y323889D01*
X106100D01*
Y338489D01*
G37*
G36*
G01X132000Y268000D02*
Y288000D01*
X200000D01*
X228000D01*
X232000D01*
Y268000D01*
X228000D01*
X200000D01*
X132000D01*
G37*
G36*
G01X199661Y304500D02*
Y308550D01*
X195611Y304500D01*
X199661D01*
G37*
G36*
G01X234500Y153950D02*
X242500D01*
Y163050D01*
X234500D01*
Y153950D01*
G37*
G36*
G01X227800Y210100D02*
Y211900D01*
X232300D01*
Y210100D01*
X227800D01*
G37*
G36*
G01X236800Y204700D02*
Y217300D01*
X238600D01*
Y204700D01*
X236800D01*
G37*
G36*
G01X232300D02*
Y217300D01*
X234100D01*
Y204700D01*
X232300D01*
G37*
G36*
G01X226000D02*
Y217300D01*
X227800D01*
Y204700D01*
X226000D01*
G37*
G36*
G01X238600Y210100D02*
Y211900D01*
X243100D01*
Y210100D01*
X238600D01*
G37*
G36*
G01Y215500D02*
Y217300D01*
X244900D01*
Y215500D01*
X238600D01*
G37*
G36*
G01X259500Y22500D02*
Y17500D01*
X279500D01*
Y22500D01*
X259500D01*
G37*
G36*
G01X290414Y140605D02*
X292114Y138905D01*
Y142305D01*
X290414Y140605D01*
G37*
G36*
G01Y249267D02*
X292114Y247567D01*
Y250967D01*
X290414Y249267D01*
G37*
G36*
G01X316009Y285321D02*
X316070Y284835D01*
X316192Y284652D01*
X316253Y284409D01*
X316374Y284166D01*
X316618Y283861D01*
Y283801D01*
X317348Y283132D01*
X317408D01*
X317652Y282949D01*
X317895Y282828D01*
X318199Y282767D01*
X318260Y282706D01*
X318868Y282645D01*
X319659Y282706D01*
X319720Y282767D01*
X319963Y282828D01*
X320206Y283010D01*
X320267D01*
X320754Y283557D01*
Y283618D01*
X320875Y283740D01*
X320936Y283983D01*
X320997Y284044D01*
X321057Y284531D01*
X321119Y284591D01*
X321057Y285565D01*
X320997Y285625D01*
X320936Y285930D01*
X320875Y285990D01*
X320814Y286233D01*
X320693Y286477D01*
X320389Y286842D01*
Y286902D01*
X319659Y287572D01*
X319476Y287632D01*
X319233Y287815D01*
X318990Y287876D01*
X318929Y287937D01*
X318442Y287997D01*
X318381Y288058D01*
X317469Y287997D01*
X317408Y287937D01*
X317165Y287876D01*
X316922Y287754D01*
X316435Y287328D01*
X316253Y287085D01*
X316070Y286720D01*
X316009Y286294D01*
X315949Y286233D01*
Y285382D01*
X316009Y285321D01*
G37*
G36*
G01X319963Y359885D02*
X320206Y360007D01*
Y359460D01*
X320145Y359399D01*
X319720Y359217D01*
X319476Y359034D01*
X319355D01*
X319294Y358852D01*
X319233Y358426D01*
X320206D01*
Y358000D01*
X318410D01*
Y358426D01*
X318868D01*
Y358730D01*
X318807Y359338D01*
X318625Y359399D01*
X318260Y359338D01*
Y359156D01*
X318199Y359095D01*
Y358426D01*
X318409D01*
Y358000D01*
X317834D01*
Y359156D01*
X317895Y359520D01*
X318078Y359764D01*
X318320Y359825D01*
X318381Y359885D01*
X318746Y359825D01*
X319050Y359581D01*
X319111Y359338D01*
X319172Y359277D01*
X319294Y359399D01*
Y359460D01*
X319355Y359520D01*
X319537Y359642D01*
X319720Y359703D01*
X319963Y359885D01*
G37*
G36*
G01X320693Y360372D02*
X320936Y360068D01*
X320997Y359825D01*
X321119Y359642D01*
X321179Y358608D01*
X321119Y358548D01*
X321057Y358183D01*
X320875Y357818D01*
X320693Y357574D01*
X320206Y357149D01*
X319720Y356906D01*
X318807Y356844D01*
X318801Y356845D01*
Y357230D01*
X318990Y357209D01*
X319598Y357270D01*
X319841Y357392D01*
X320145Y357635D01*
X320206D01*
X320571Y358061D01*
X320693Y358304D01*
X320754Y358730D01*
X320814Y358791D01*
X320754Y359520D01*
X320693Y359581D01*
X320632Y359825D01*
X320328Y360190D01*
X319841Y360615D01*
X319598Y360676D01*
X319537Y360737D01*
X319111Y360798D01*
X318503Y360737D01*
X318442Y360676D01*
X318199Y360615D01*
X317834Y360311D01*
X317713D01*
Y360190D01*
X317408Y359825D01*
Y359703D01*
X317348Y359642D01*
X317287Y359277D01*
X317226Y359217D01*
X317287Y358487D01*
X317348Y358426D01*
X317408Y358183D01*
X317591Y357939D01*
Y357878D01*
X318078Y357453D01*
X318442Y357270D01*
X318800Y357230D01*
Y356845D01*
X318320Y356906D01*
X317834Y357149D01*
X317591Y357331D01*
X317165Y357818D01*
X316983Y358183D01*
X316922Y358548D01*
X316861Y358608D01*
Y359399D01*
X316922Y359460D01*
X316983Y359825D01*
X317104Y360068D01*
X317348Y360372D01*
Y360433D01*
X317834Y360859D01*
X318078Y360980D01*
X318320Y361041D01*
X318381Y361102D01*
X319476Y361163D01*
X319537Y361102D01*
X319841Y361041D01*
X320206Y360859D01*
X320693Y360433D01*
Y360372D01*
G37*
G36*
G01X323186Y257527D02*
X323673Y257588D01*
X323733Y257648D01*
X324463Y257709D01*
X324524Y257770D01*
X325315Y257831D01*
X325376Y257892D01*
X326106Y257953D01*
X326166Y258013D01*
X326896Y258074D01*
X326957Y258135D01*
X327687Y258196D01*
X327748Y258257D01*
X328478Y258317D01*
X328538Y258378D01*
X329329Y258439D01*
X329390Y258500D01*
X330120Y258561D01*
X330180Y258622D01*
X330910Y258682D01*
X330971Y258743D01*
X331701Y258804D01*
X331762Y258865D01*
X332491Y258926D01*
X332552Y258987D01*
X333282Y259047D01*
X333343Y259108D01*
X334133Y259169D01*
X334194Y259230D01*
X334924Y259291D01*
X334985Y259352D01*
X335411Y259412D01*
Y263852D01*
X335168Y264035D01*
X334863Y264156D01*
X334620Y264339D01*
X334316Y264460D01*
X334073Y264643D01*
X333891Y264704D01*
X333647Y264886D01*
X333343Y265007D01*
X333100Y265190D01*
X332796Y265312D01*
X332552Y265494D01*
X332248Y265616D01*
X332005Y265798D01*
X331822Y265859D01*
X331579Y266041D01*
X331275Y266163D01*
X331032Y266346D01*
X330728Y266467D01*
X330485Y266650D01*
X330180Y266771D01*
X329937Y266954D01*
X329633Y267076D01*
X329390Y267258D01*
X329207Y267319D01*
X328964Y267501D01*
X328660Y267623D01*
X328417Y267805D01*
X328113Y267927D01*
X327869Y268109D01*
X327808D01*
X327687Y268231D01*
X327748Y268292D01*
X328843Y268353D01*
X328903Y268413D01*
X329998Y268474D01*
X330059Y268535D01*
X331154Y268596D01*
X331214Y268657D01*
X332370Y268718D01*
X332431Y268778D01*
X333526Y268839D01*
X333586Y268900D01*
X334681Y268961D01*
X334742Y269022D01*
X335411Y269082D01*
Y273522D01*
X335107Y273644D01*
X334863Y273826D01*
X334681Y273887D01*
X334438Y274070D01*
X334255Y274130D01*
X334012Y274313D01*
X333830Y274374D01*
X333586Y274556D01*
X333282Y274678D01*
X333039Y274860D01*
X332856Y274921D01*
X332613Y275104D01*
X332431Y275165D01*
X332187Y275347D01*
X332005Y275407D01*
X331762Y275590D01*
X331579Y275651D01*
X331336Y275833D01*
X331154Y275894D01*
X330910Y276077D01*
X330728Y276137D01*
X330485Y276320D01*
X330302Y276381D01*
X330059Y276563D01*
X329876Y276624D01*
X329633Y276807D01*
X329329Y276928D01*
X329086Y277111D01*
X328903Y277171D01*
X328660Y277354D01*
X328478Y277415D01*
X328234Y277597D01*
X328052Y277658D01*
X327808Y277841D01*
X327626Y277901D01*
X327383Y278084D01*
X327200Y278144D01*
X326957Y278327D01*
X326774Y278388D01*
X326531Y278570D01*
X326349Y278631D01*
X326106Y278813D01*
X325923Y278874D01*
X325680Y279057D01*
X325376Y279178D01*
X325132Y279361D01*
X324950Y279422D01*
X324707Y279604D01*
X324524Y279665D01*
X324281Y279848D01*
X324098Y279908D01*
X323855Y280091D01*
X323673Y280152D01*
X323430Y280334D01*
X323247Y280395D01*
X323004Y280577D01*
X322821Y280638D01*
X322578Y280820D01*
X322517D01*
X322456Y280881D01*
Y275772D01*
X322700Y275712D01*
X323125Y275469D01*
X323369Y275407D01*
X323673Y275225D01*
X323916Y275165D01*
X324098Y275043D01*
X324342Y274982D01*
X324646Y274800D01*
X324889Y274739D01*
X325193Y274556D01*
X325437Y274495D01*
X325619Y274374D01*
X325862Y274313D01*
X326166Y274130D01*
X326409Y274070D01*
X326714Y273887D01*
X326957Y273826D01*
X327139Y273705D01*
X327383Y273644D01*
X327687Y273461D01*
X327930Y273401D01*
X328234Y273218D01*
X328478Y273157D01*
X328660Y273036D01*
X328903Y272975D01*
X329207Y272793D01*
X329450Y272731D01*
X329755Y272549D01*
X329998Y272488D01*
X330180Y272367D01*
X330424Y272306D01*
X330545Y272184D01*
X330485Y272124D01*
X329268Y272063D01*
X329207Y272002D01*
X327930Y271941D01*
X327869Y271880D01*
X326592Y271819D01*
X326531Y271759D01*
X325193Y271698D01*
X325132Y271637D01*
X323855Y271576D01*
X323794Y271515D01*
X322517Y271454D01*
X322456Y271394D01*
Y266893D01*
X322882Y266711D01*
X323125Y266528D01*
X323551Y266346D01*
X323794Y266163D01*
X324220Y265981D01*
X324463Y265798D01*
X324889Y265616D01*
X325132Y265433D01*
X325437Y265312D01*
X325680Y265129D01*
X326106Y264947D01*
X326349Y264764D01*
X326774Y264582D01*
X327018Y264399D01*
X327322Y264278D01*
X327565Y264095D01*
X327991Y263913D01*
X328234Y263730D01*
X328660Y263548D01*
X328903Y263365D01*
X329329Y263183D01*
X329572Y263000D01*
X329876Y262879D01*
X330120Y262696D01*
X330545Y262514D01*
X330667Y262393D01*
X330606Y262331D01*
X328660Y262271D01*
X328599Y262210D01*
X326592Y262149D01*
X326531Y262088D01*
X324524Y262028D01*
X324463Y261967D01*
X322456Y261906D01*
Y257405D01*
X323186Y257527D01*
G37*
G36*
G01X323004Y288241D02*
X323065Y288301D01*
X323855Y288362D01*
X323916Y288423D01*
X324646Y288484D01*
X324707Y288544D01*
X325437Y288606D01*
X325497Y288666D01*
X326227Y288727D01*
X326288Y288788D01*
X327018Y288849D01*
X327079Y288909D01*
X327808Y288970D01*
X327869Y289031D01*
X328660Y289092D01*
X328721Y289153D01*
X329450Y289214D01*
X329511Y289274D01*
X330241Y289335D01*
X330302Y289396D01*
X331032Y289457D01*
X331093Y289518D01*
X331822Y289578D01*
X331883Y289639D01*
X332613Y289700D01*
X332674Y289761D01*
X333465Y289822D01*
X333526Y289883D01*
X334255Y289943D01*
X334316Y290004D01*
X335046Y290065D01*
X335107Y290126D01*
X335411D01*
Y294626D01*
X335168Y294748D01*
X334924Y294931D01*
X334620Y295052D01*
X334377Y295235D01*
X334073Y295356D01*
X333830Y295539D01*
X333526Y295661D01*
X333282Y295843D01*
X332978Y295965D01*
X332735Y296147D01*
X332431Y296269D01*
X332187Y296451D01*
X332005Y296512D01*
X331762Y296694D01*
X331457Y296816D01*
X331214Y296998D01*
X330910Y297120D01*
X330667Y297303D01*
X330363Y297424D01*
X330120Y297607D01*
X329815Y297728D01*
X329572Y297911D01*
X329268Y298032D01*
X329025Y298215D01*
X328843Y298276D01*
X328599Y298458D01*
X328295Y298580D01*
X328052Y298762D01*
X327687Y298945D01*
X327748Y299006D01*
X328234Y299066D01*
X328964Y299127D01*
X329329Y299188D01*
X330180Y299249D01*
X330241Y299309D01*
X331336Y299370D01*
X331397Y299431D01*
X332491Y299492D01*
X332552Y299553D01*
X333708Y299614D01*
X333769Y299674D01*
X334863Y299735D01*
X334924Y299796D01*
X335411D01*
Y304236D01*
X335168Y304357D01*
X334924Y304540D01*
X334742Y304601D01*
X334498Y304783D01*
X334316Y304844D01*
X334073Y305027D01*
X333891Y305087D01*
X333647Y305270D01*
X333465Y305331D01*
X333221Y305513D01*
X333039Y305574D01*
X332796Y305756D01*
X332613Y305817D01*
X332370Y306000D01*
X332187Y306061D01*
X331944Y306243D01*
X331762Y306304D01*
X331519Y306486D01*
X331214Y306608D01*
X330971Y306791D01*
X330789Y306851D01*
X330545Y307033D01*
X330363Y307094D01*
X330120Y307277D01*
X329937Y307338D01*
X329694Y307520D01*
X329511Y307581D01*
X329268Y307763D01*
X329086Y307824D01*
X328843Y308007D01*
X328660Y308068D01*
X328417Y308250D01*
X328234Y308311D01*
X327991Y308493D01*
X327808Y308554D01*
X327565Y308737D01*
X327383Y308797D01*
X327139Y308980D01*
X326835Y309102D01*
X326592Y309284D01*
X326409Y309345D01*
X326166Y309527D01*
X325984Y309588D01*
X325741Y309770D01*
X325558Y309831D01*
X325315Y310014D01*
X325132Y310074D01*
X324889Y310257D01*
X324707Y310318D01*
X324463Y310500D01*
X324281Y310561D01*
X324038Y310744D01*
X323855Y310804D01*
X323612Y310987D01*
X323430Y311048D01*
X323186Y311230D01*
X322882Y311352D01*
X322639Y311534D01*
X322517Y311595D01*
X322456D01*
Y306547D01*
X322943Y306304D01*
X323186Y306243D01*
X323490Y306061D01*
X323733Y306000D01*
X323916Y305878D01*
X324159Y305817D01*
X324463Y305635D01*
X324707Y305574D01*
X325011Y305391D01*
X325254Y305331D01*
X325437Y305209D01*
X325680Y305148D01*
X325984Y304966D01*
X326227Y304905D01*
X326531Y304722D01*
X326774Y304662D01*
X326957Y304540D01*
X327200Y304479D01*
X327504Y304297D01*
X327748Y304236D01*
X328052Y304054D01*
X328295Y303993D01*
X328478Y303871D01*
X328721Y303810D01*
X329025Y303628D01*
X329268Y303567D01*
X329572Y303385D01*
X329815Y303324D01*
X329998Y303202D01*
X330241Y303141D01*
X330545Y302959D01*
X330485Y302898D01*
X329511Y302837D01*
X329146Y302776D01*
X328173Y302715D01*
X327808Y302655D01*
X326835Y302594D01*
X326470Y302533D01*
X325497Y302472D01*
X325132Y302411D01*
X324159Y302350D01*
X323794Y302290D01*
X322821Y302229D01*
X322456Y302168D01*
Y297667D01*
X322517D01*
X322761Y297485D01*
X323186Y297303D01*
X323430Y297120D01*
X323855Y296938D01*
X324098Y296755D01*
X324524Y296573D01*
X324767Y296390D01*
X325072Y296269D01*
X325315Y296086D01*
X325741Y295904D01*
X325984Y295721D01*
X326409Y295539D01*
X326653Y295356D01*
X327079Y295174D01*
X327322Y294991D01*
X327626Y294870D01*
X327869Y294687D01*
X328295Y294505D01*
X328538Y294322D01*
X328964Y294140D01*
X329207Y293957D01*
X329633Y293775D01*
X329876Y293593D01*
X330180Y293471D01*
X330424Y293289D01*
X330667Y293167D01*
X330606Y293106D01*
X329268Y293045D01*
X328538Y292984D01*
X327200Y292924D01*
X326470Y292863D01*
X325132Y292802D01*
X324281Y292741D01*
X323065Y292680D01*
X322456Y292620D01*
Y288180D01*
X323004Y288241D01*
G37*
G36*
G01X322821Y281794D02*
X322882Y281733D01*
X323369Y281672D01*
X323430Y281611D01*
X323916Y281550D01*
X323977Y281490D01*
X324524Y281429D01*
X324585Y281368D01*
X325072Y281307D01*
X325132Y281246D01*
X325619Y281185D01*
X325680Y281125D01*
X326227Y281064D01*
X326288Y281003D01*
X326774Y280942D01*
X326835Y280881D01*
X327322Y280820D01*
X327383Y280760D01*
X327930Y280699D01*
X327991Y280638D01*
X328478Y280577D01*
X328538Y280517D01*
X329025Y280456D01*
X329086Y280395D01*
X329633Y280334D01*
X329694Y280273D01*
X330180Y280212D01*
X330241Y280152D01*
X330728Y280091D01*
X330789Y280030D01*
X331336Y279969D01*
X331397Y279908D01*
X331883Y279848D01*
X331944Y279787D01*
X332431Y279726D01*
X332491Y279665D01*
X333039Y279604D01*
X333100Y279543D01*
X333586Y279483D01*
X333647Y279422D01*
X334133Y279361D01*
X334194Y279300D01*
X334742Y279239D01*
X334803Y279178D01*
X335289Y279118D01*
X335350Y279057D01*
X335411D01*
Y284409D01*
X335046Y284470D01*
X334985Y284531D01*
X334498Y284591D01*
X334438Y284652D01*
X333891Y284713D01*
X333830Y284774D01*
X333343Y284835D01*
X333282Y284895D01*
X332796Y284956D01*
X332735Y285017D01*
X332187Y285078D01*
X332127Y285139D01*
X331640Y285200D01*
X331579Y285260D01*
X331093Y285321D01*
X331032Y285382D01*
X330485Y285443D01*
X330424Y285504D01*
X329937Y285565D01*
X329876Y285625D01*
X329390Y285686D01*
X329329Y285747D01*
X328781Y285808D01*
X328721Y285869D01*
X328234Y285930D01*
X328173Y285990D01*
X327687Y286051D01*
X327626Y286112D01*
X327139Y286173D01*
X327079Y286233D01*
X326531Y286294D01*
X326470Y286355D01*
X325984Y286416D01*
X325923Y286477D01*
X325437Y286537D01*
X325376Y286598D01*
X324828Y286659D01*
X324767Y286720D01*
X324281Y286781D01*
X324220Y286842D01*
X323733Y286902D01*
X323673Y286963D01*
X323125Y287024D01*
X323065Y287085D01*
X322578Y287146D01*
X322517Y287207D01*
X322456D01*
Y281854D01*
X322821Y281794D01*
G37*
G36*
G01X322213Y337139D02*
X322274Y336409D01*
X322335Y336348D01*
X322396Y335983D01*
X322456Y335923D01*
X322517Y335619D01*
X322578Y335558D01*
X322639Y335315D01*
X322700Y335254D01*
X322761Y335011D01*
X322882Y334767D01*
X323065Y334524D01*
Y334463D01*
X323308Y334159D01*
Y334098D01*
X323733Y333612D01*
Y333551D01*
X324403Y332882D01*
X324342Y332821D01*
X323855Y332882D01*
X323794Y332943D01*
X323308Y333004D01*
X323247Y333064D01*
X322761Y333125D01*
X322700Y333186D01*
X322456D01*
Y328564D01*
X322882Y328503D01*
X322943Y328442D01*
X323490Y328381D01*
X323551Y328320D01*
X324038Y328259D01*
X324098Y328199D01*
X324585Y328138D01*
X324646Y328077D01*
X325193Y328016D01*
X325254Y327956D01*
X325741Y327894D01*
X325802Y327834D01*
X326288Y327773D01*
X326349Y327712D01*
X326835Y327651D01*
X326896Y327591D01*
X327444Y327530D01*
X327504Y327469D01*
X327991Y327408D01*
X328052Y327347D01*
X328538Y327287D01*
X328599Y327226D01*
X329146Y327165D01*
X329207Y327104D01*
X329694Y327043D01*
X329755Y326982D01*
X330241Y326922D01*
X330302Y326861D01*
X330850Y326800D01*
X330910Y326739D01*
X331397Y326678D01*
X331457Y326617D01*
X331944Y326557D01*
X332005Y326496D01*
X332491Y326435D01*
X332552Y326374D01*
X333100Y326313D01*
X333161Y326252D01*
X333647Y326192D01*
X333708Y326131D01*
X334194Y326070D01*
X334255Y326009D01*
X334803Y325948D01*
X334863Y325887D01*
X335350Y325827D01*
X335411Y325766D01*
Y330814D01*
X334863Y330875D01*
X334803Y330935D01*
X334316Y330996D01*
X334255Y331057D01*
X333769Y331118D01*
X333708Y331179D01*
X333221Y331240D01*
X333161Y331300D01*
X332674Y331361D01*
X332613Y331422D01*
X332066Y331483D01*
X332005Y331544D01*
X331519Y331605D01*
X331457Y331665D01*
X330971Y331726D01*
X330910Y331787D01*
X330424Y331848D01*
X330363Y331909D01*
X329876Y331970D01*
X329815Y332030D01*
X329329Y332091D01*
X329268Y332152D01*
X328903Y332213D01*
X328843Y332274D01*
X328538Y332334D01*
X328478Y332395D01*
X328173Y332456D01*
X327322Y332882D01*
X327018Y333125D01*
X326957D01*
X326349Y333672D01*
X326106Y333976D01*
X325862Y334463D01*
X325802Y334950D01*
X325741Y335011D01*
X325802Y335619D01*
X326106Y335983D01*
X326288Y336105D01*
X326774Y336166D01*
X327565Y336105D01*
X327626Y336044D01*
X328173Y335983D01*
X328234Y335923D01*
X328781Y335862D01*
X328843Y335801D01*
X329390Y335740D01*
X329450Y335680D01*
X329937Y335619D01*
X329998Y335558D01*
X330545Y335497D01*
X330606Y335436D01*
X331093Y335375D01*
X331154Y335315D01*
X331640Y335254D01*
X331701Y335193D01*
X332248Y335132D01*
X332309Y335071D01*
X332796Y335011D01*
X332856Y334950D01*
X333404Y334889D01*
X333465Y334828D01*
X333951Y334767D01*
X334012Y334706D01*
X334498Y334646D01*
X334559Y334585D01*
X335107Y334524D01*
X335168Y334463D01*
X335411D01*
Y339389D01*
X335107Y339450D01*
X335046Y339511D01*
X334498Y339572D01*
X334438Y339633D01*
X333951Y339694D01*
X333891Y339754D01*
X333343Y339815D01*
X333282Y339876D01*
X332796Y339937D01*
X332735Y339998D01*
X332248Y340058D01*
X332187Y340119D01*
X331640Y340180D01*
X331579Y340241D01*
X331093Y340302D01*
X331032Y340363D01*
X330485Y340423D01*
X330424Y340484D01*
X329937Y340545D01*
X329876Y340606D01*
X329390Y340667D01*
X329329Y340728D01*
X328781Y340788D01*
X328721Y340849D01*
X328234Y340910D01*
X328173Y340971D01*
X327626Y341031D01*
X327565Y341093D01*
X326957Y341153D01*
X326896Y341214D01*
X326227Y341275D01*
X326166Y341336D01*
X325193Y341396D01*
X324463Y341336D01*
X324403Y341275D01*
X324098Y341214D01*
X324038Y341153D01*
X323794Y341093D01*
X323551Y340910D01*
X323490D01*
X323004Y340484D01*
X322639Y340058D01*
X322456Y339694D01*
X322396Y339450D01*
X322335Y339389D01*
X322274Y338964D01*
X322213Y338903D01*
X322152Y337930D01*
Y337200D01*
X322213Y337139D01*
G37*
G36*
G01X322700Y322421D02*
X322943Y322239D01*
X323125Y322178D01*
X323369Y321995D01*
X323551Y321934D01*
X323794Y321752D01*
X323977Y321691D01*
X324220Y321509D01*
X324524Y321387D01*
X324767Y321204D01*
X324950Y321144D01*
X325193Y320961D01*
X325376Y320900D01*
X325619Y320718D01*
X325802Y320657D01*
X326045Y320475D01*
X326349Y320353D01*
X326592Y320170D01*
X326774Y320110D01*
X327018Y319927D01*
X327200Y319867D01*
X327444Y319684D01*
X327626Y319623D01*
X327869Y319441D01*
X328052Y319380D01*
X328295Y319198D01*
X328599Y319076D01*
X328843Y318893D01*
X329025Y318833D01*
X329268Y318650D01*
X329450Y318589D01*
X329694Y318407D01*
X329755D01*
X329876Y318285D01*
X329815Y318224D01*
X328843Y318163D01*
X328781Y318103D01*
X327626Y318042D01*
X327565Y317981D01*
X326349Y317920D01*
X326288Y317859D01*
X325132Y317799D01*
X325072Y317738D01*
X323855Y317677D01*
X323794Y317616D01*
X322639Y317556D01*
X322578Y317494D01*
X322456D01*
Y312629D01*
X322517Y312690D01*
X323125Y312751D01*
X323186Y312811D01*
X323794Y312872D01*
X323855Y312933D01*
X324403Y312994D01*
X324463Y313055D01*
X325072Y313116D01*
X325132Y313176D01*
X325741Y313237D01*
X325802Y313298D01*
X326349Y313359D01*
X326409Y313420D01*
X327018Y313480D01*
X327079Y313541D01*
X327687Y313602D01*
X327748Y313663D01*
X328295Y313724D01*
X328356Y313785D01*
X328964Y313845D01*
X329025Y313906D01*
X329633Y313967D01*
X329694Y314028D01*
X330241Y314089D01*
X330302Y314150D01*
X330910Y314210D01*
X330971Y314271D01*
X331579Y314332D01*
X331640Y314393D01*
X332187Y314454D01*
X332248Y314515D01*
X332856Y314575D01*
X332917Y314636D01*
X333526Y314697D01*
X333586Y314757D01*
X334133Y314819D01*
X334194Y314879D01*
X334803Y314940D01*
X334863Y315001D01*
X335472Y315062D01*
X335533Y315122D01*
X335776Y315001D01*
X336019Y314819D01*
X336323Y314697D01*
X336567Y314515D01*
X336749Y314454D01*
X336992Y314271D01*
X337174Y314210D01*
X337418Y314028D01*
X337600Y313967D01*
X337844Y313785D01*
X338148Y313663D01*
X338391Y313480D01*
X338574Y313420D01*
X338817Y313237D01*
X338999Y313176D01*
X339243Y312994D01*
X339425Y312933D01*
X339668Y312751D01*
X339972Y312629D01*
X340216Y312446D01*
X340398Y312386D01*
X340641Y312203D01*
X340824Y312143D01*
X341067Y311960D01*
X341250Y311899D01*
X341493Y311717D01*
X341797Y311595D01*
X341919Y311474D01*
Y316582D01*
X341736Y316643D01*
X341493Y316826D01*
X341310Y316886D01*
X341067Y317069D01*
X340885Y317130D01*
X340641Y317312D01*
X340337Y317434D01*
X340094Y317616D01*
X339911Y317677D01*
X339668Y317859D01*
X339486Y317920D01*
X339243Y318103D01*
X339060Y318163D01*
X338817Y318346D01*
X338513Y318468D01*
X338269Y318650D01*
X338087Y318711D01*
X337844Y318893D01*
X337661Y318954D01*
X337418Y319137D01*
X337235Y319198D01*
X336992Y319380D01*
X336810Y319441D01*
X336567Y319623D01*
X336262Y319745D01*
X336019Y319927D01*
X335837Y319988D01*
X335593Y320170D01*
X335411Y320231D01*
X335168Y320414D01*
X334985Y320475D01*
X334742Y320657D01*
X334438Y320779D01*
X334194Y320961D01*
X334012Y321022D01*
X333769Y321204D01*
X333586Y321265D01*
X333343Y321448D01*
X333161Y321509D01*
X332917Y321691D01*
X332613Y321813D01*
X332370Y321995D01*
X332187Y322056D01*
X331944Y322239D01*
X331762Y322299D01*
X331519Y322482D01*
X331336Y322543D01*
X331093Y322725D01*
X330910Y322786D01*
X330667Y322968D01*
X330363Y323090D01*
X330120Y323272D01*
X329937Y323333D01*
X329694Y323516D01*
X329511Y323576D01*
X329268Y323759D01*
X329086Y323820D01*
X328843Y324002D01*
X328538Y324124D01*
X328295Y324306D01*
X328113Y324367D01*
X327869Y324550D01*
X327687Y324610D01*
X327444Y324793D01*
X327261Y324854D01*
X327018Y325036D01*
X326714Y325158D01*
X326470Y325340D01*
X326288Y325401D01*
X326045Y325583D01*
X325862Y325644D01*
X325619Y325827D01*
X325437Y325887D01*
X325193Y326070D01*
X324889Y326192D01*
X324646Y326374D01*
X324463Y326435D01*
X324220Y326617D01*
X324038Y326678D01*
X323794Y326861D01*
X323612Y326922D01*
X323369Y327104D01*
X323186Y327165D01*
X322943Y327347D01*
X322639Y327469D01*
X322517Y327591D01*
X322396D01*
Y322543D01*
X322700Y322421D01*
G37*
G36*
G01X322213Y352587D02*
X322274Y351857D01*
X322335Y351796D01*
X322396Y351371D01*
X322456Y351310D01*
X322517Y351006D01*
X322639Y350824D01*
X322700Y350580D01*
X323004Y349972D01*
X323247Y349668D01*
Y349607D01*
X323551Y349242D01*
Y349181D01*
X324463Y348269D01*
X324403Y348208D01*
X323977Y348269D01*
X323916Y348330D01*
X323430Y348391D01*
X323369Y348452D01*
X322882Y348512D01*
X322821Y348573D01*
X322517Y348634D01*
X322456D01*
Y344012D01*
X322517Y343951D01*
X323004Y343890D01*
X323065Y343829D01*
X323612Y343769D01*
X323673Y343707D01*
X324159Y343647D01*
X324220Y343586D01*
X324707Y343525D01*
X324767Y343464D01*
X325315Y343404D01*
X325376Y343343D01*
X325862Y343282D01*
X325923Y343221D01*
X326409Y343160D01*
X326470Y343099D01*
X326957Y343039D01*
X327018Y342978D01*
X327565Y342917D01*
X327626Y342856D01*
X328113Y342795D01*
X328173Y342735D01*
X328660Y342674D01*
X328721Y342613D01*
X329268Y342552D01*
X329329Y342491D01*
X329815Y342430D01*
X329876Y342370D01*
X330363Y342309D01*
X330424Y342248D01*
X330971Y342187D01*
X331032Y342126D01*
X331519Y342065D01*
X331579Y342005D01*
X332066Y341944D01*
X332127Y341883D01*
X332613Y341822D01*
X332674Y341761D01*
X333221Y341700D01*
X333282Y341640D01*
X333769Y341579D01*
X333830Y341518D01*
X334316Y341457D01*
X334377Y341396D01*
X334924Y341336D01*
X334985Y341275D01*
X335411Y341214D01*
Y346201D01*
X335046Y346262D01*
X334985Y346323D01*
X334438Y346383D01*
X334377Y346444D01*
X333891Y346505D01*
X333830Y346566D01*
X333343Y346627D01*
X333282Y346688D01*
X332796Y346748D01*
X332735Y346809D01*
X332248Y346870D01*
X332187Y346931D01*
X331640Y346992D01*
X331579Y347053D01*
X331093Y347113D01*
X331032Y347174D01*
X330545Y347235D01*
X330485Y347296D01*
X329998Y347357D01*
X329937Y347418D01*
X329450Y347478D01*
X329390Y347539D01*
X328964Y347600D01*
X328903Y347661D01*
X328599Y347722D01*
X328538Y347783D01*
X328295Y347843D01*
X328234Y347904D01*
X327991Y347965D01*
X327930Y348026D01*
X327687Y348087D01*
X327444Y348269D01*
X327261Y348330D01*
X326957Y348573D01*
X326896D01*
X326409Y348999D01*
Y349060D01*
X326045Y349485D01*
X325862Y349850D01*
X325802Y350337D01*
X325741Y350398D01*
X325802Y351006D01*
X325984Y351249D01*
Y351371D01*
X326106D01*
X326227Y351493D01*
X326592Y351553D01*
X326653Y351614D01*
X327383Y351553D01*
X327444Y351493D01*
X328052Y351431D01*
X328113Y351371D01*
X328660Y351310D01*
X328721Y351249D01*
X329207Y351188D01*
X329268Y351128D01*
X329815Y351067D01*
X329876Y351006D01*
X330363Y350945D01*
X330424Y350884D01*
X330910Y350824D01*
X330971Y350763D01*
X331519Y350702D01*
X331579Y350641D01*
X332066Y350580D01*
X332127Y350519D01*
X332674Y350459D01*
X332735Y350398D01*
X333221Y350337D01*
X333282Y350276D01*
X333769Y350215D01*
X333830Y350154D01*
X334377Y350094D01*
X334438Y350033D01*
X334924Y349972D01*
X334985Y349911D01*
X335411Y349850D01*
Y354837D01*
X334924Y354898D01*
X334863Y354959D01*
X334377Y355020D01*
X334316Y355081D01*
X333769Y355142D01*
X333708Y355202D01*
X333221Y355263D01*
X333161Y355324D01*
X332613Y355385D01*
X332552Y355446D01*
X332066Y355507D01*
X332005Y355567D01*
X331519Y355628D01*
X331457Y355689D01*
X330910Y355750D01*
X330850Y355811D01*
X330363Y355871D01*
X330302Y355932D01*
X329755Y355993D01*
X329694Y356054D01*
X329207Y356115D01*
X329146Y356176D01*
X328599Y356236D01*
X328538Y356297D01*
X328052Y356358D01*
X327991Y356419D01*
X327444Y356480D01*
X327383Y356541D01*
X326774Y356601D01*
X326714Y356662D01*
X325984Y356723D01*
X325923Y356784D01*
X324342Y356723D01*
X324281Y356662D01*
X324038Y356601D01*
X323977Y356541D01*
X323855D01*
X323612Y356358D01*
X323551D01*
X323065Y355932D01*
X322639Y355446D01*
X322396Y354959D01*
X322335Y354655D01*
X322274Y354594D01*
X322213Y353986D01*
X322152Y353925D01*
Y352648D01*
X322213Y352587D01*
G37*
G54D10*
G01X275941Y383109D02*
G03X286414I5237J0D01*
G01X307436D02*
G03X317909I5236J0D01*
G01X338931D02*
G03X349404I5236J0D01*
G01X370427D02*
G03X380899I5236J0D01*
G01X401922D02*
G03X412394I5236J0D01*
G01X433417D02*
G03X443889I5236J0D01*
G54D20*
G01X57200Y317689D02*
X56100D01*
G01X59900D02*
X58800D01*
G01X123500Y324189D02*
Y324289D01*
X102900D01*
G01X107000Y331189D02*
X103000Y327189D01*
G01Y338189D02*
Y314689D01*
G01Y338189D02*
X123500D01*
G01X107000Y331189D02*
X103000Y335189D01*
G01X123500Y338189D02*
Y324189D01*
G01X167500Y333500D02*
X171500D01*
G01X194000Y338500D02*
X198000D01*
G01X211000Y291200D02*
Y290100D01*
G01Y293900D02*
Y292800D01*
G01X299000Y121000D02*
X295000D01*
G54D11*
G01X-176139Y-183003D02*
G02I-12000J0D01*
G01X-181289D02*
G02I-6850J0D01*
G01X-172139D02*
X-204139D01*
G01X-188139Y-199003D02*
Y-167003D01*
G01X-172139Y-199003D02*
Y-279003D01*
G01D02*
X1178561D01*
G01X-172139Y-234503D02*
X1178561D01*
G01X-172139Y-199003D02*
X1178561D01*
G01X62000Y328689D02*
Y333689D01*
G01X80500Y288189D02*
Y283189D01*
G01Y296189D02*
Y291189D01*
G01Y304189D02*
Y299189D01*
G01Y333689D02*
Y328689D01*
G01X103000Y314689D02*
Y325689D01*
G01X136500Y333000D02*
X141500D01*
G01X149500Y316000D02*
X144500D01*
G01X157500D02*
X152500D01*
G01Y333000D02*
X157500D01*
G01X144500D02*
X149500D01*
G01X160500D02*
X165500D01*
G01X242800Y151500D02*
X250500D01*
G01X240700Y309000D02*
X257300D01*
G01X259000Y298500D02*
Y293500D01*
G01Y306500D02*
Y301500D01*
G01X391061Y-199003D02*
Y-279003D01*
G01X528561Y-199003D02*
Y-279003D01*
G01X643561Y-199003D02*
Y-279003D01*
G01X811061Y-199003D02*
Y-279003D01*
G01X981061Y-199003D02*
Y-279003D01*
G01X1178561Y-199003D02*
Y-279003D01*
G01X1210561Y-183003D02*
X1178561D01*
G01X1206561D02*
G02I-12000J0D01*
G01X1201411D02*
G02I-6850J0D01*
G01X1194561Y-199003D02*
Y-167003D01*
G54D12*
G01X13591Y-105354D02*
X38787D01*
G01X13591Y363425D02*
X38787D01*
G01X262196Y-105354D02*
X237000D01*
G01Y363425D02*
X262196D01*
G01X306200Y290500D02*
G02I-4200J0D01*
G01Y310500D02*
G02I-4200J0D01*
G01Y300500D02*
G02I-4200J0D01*
G01X349409Y-20709D02*
Y-51418D01*
G01Y309489D02*
Y278780D01*
G01X373031Y-20709D02*
Y-51418D01*
G01X411819Y258071D02*
X386622D01*
G01X411819Y265945D02*
X386622D01*
G01X373031Y309489D02*
Y278780D01*
G01X485441Y-105354D02*
X460244D01*
G01Y363425D02*
X485441D01*
G01X506495Y116437D02*
Y141634D01*
G01X560333Y-7874D02*
X535137D01*
G01Y265945D02*
X560333D01*
G01X588976Y116437D02*
Y141634D01*
G01X708848Y-105354D02*
X683652D01*
G01Y-7874D02*
X708848D01*
G01X683652Y0D02*
X708848D01*
G01X683652Y363425D02*
X708848D01*
G54D13*
G01X290701Y141594D02*
Y139594D01*
G01X295400Y158400D02*
X292550D01*
Y161100D01*
G01X290701Y250256D02*
Y248256D01*
G54D14*
G01X248650Y211000D02*
G03I-13650J0D01*
G54D15*
G01X13592Y258071D02*
X38788D01*
G01X13592Y265945D02*
X38788D01*
G01X133465Y141634D02*
Y116437D01*
G01X133470Y141630D02*
Y116433D01*
G01X187303Y-7874D02*
X162107D01*
G01Y265945D02*
X187303D01*
G01X187308Y265941D02*
X162112D01*
G01X215946Y141634D02*
Y116437D01*
G01X215951Y116433D02*
Y141630D01*
G01X310622Y-7874D02*
X335818D01*
G01X310622Y0D02*
X335818D01*
G54D16*
G01X107100Y300300D02*
Y307000D01*
G01X116700Y300100D02*
X110000D01*
G01X308500Y311650D02*
Y316650D01*
X303500D01*
G54D17*
G01X262670Y27590D02*
X262010D01*
G01X262110Y27680D02*
X262770D01*
G01X262860Y27790D02*
X262210D01*
G01X262310Y27880D02*
X262960D01*
G01X263060Y27990D02*
X262400D01*
G01X262500Y28090D02*
X263150D01*
G01X263250Y28180D02*
X262600D01*
G01X262690Y28290D02*
X263350D01*
G01X263440Y28380D02*
X262790D01*
G01X262880Y28490D02*
X263540D01*
G01X263640Y28590D02*
X262980D01*
G01X263080Y28680D02*
X263730D01*
G01X263830Y28790D02*
X263185D01*
G01X263180D02*
X263230D01*
G01X263270Y28880D02*
X263310D01*
G01X263270D02*
X263920D01*
G01X264020Y28990D02*
X263370D01*
G01X263470Y29090D02*
X264120D01*
G01X264220Y29180D02*
X263560D01*
G01X263660Y29290D02*
X264310D01*
G01X264410Y29380D02*
X263750D01*
G01X263850Y29490D02*
X264510D01*
G01X264600Y29590D02*
X263950D01*
G01X264050Y29680D02*
X264700D01*
G01X264790Y29790D02*
X264140D01*
G01X266530Y28780D02*
X266640D01*
G01X266530Y28790D02*
Y28780D01*
G01X266330Y31140D02*
X266530Y28790D01*
G01X266630Y28880D02*
X266520D01*
G01X266525D02*
X272120D01*
G01X272185Y28790D02*
X266530D01*
G01X266770Y27740D02*
X267660D01*
G01X266730Y27780D02*
X266770Y27740D01*
G01X266730Y28460D02*
Y27780D01*
G01X266700Y28530D02*
X266730Y28460D01*
G01X266550Y28690D02*
X266700Y28530D01*
G01X266540Y28710D02*
X266550Y28690D01*
G01X266530Y28770D02*
X266540Y28710D01*
G01X267700Y27790D02*
X266730D01*
G01Y27990D02*
X267700D01*
G01Y28180D02*
X266730D01*
G01Y28380D02*
X267700D01*
G01X266980Y29090D02*
X266510D01*
G01X266490Y29180D02*
X266960D01*
G01X266950Y29380D02*
X266480D01*
G01X266460Y29590D02*
X266930D01*
G01X266910Y29790D02*
X266440D01*
G01X266650Y28590D02*
X272430D01*
G01X266970Y29160D02*
X266750Y31740D01*
G01X266970Y29090D02*
Y29160D01*
G01X267070Y29000D02*
X266970Y29090D01*
G01X271170Y29000D02*
X267070D01*
G01X266920Y29680D02*
X266460D01*
G01X266470Y29490D02*
X266940D01*
G01X266960Y29290D02*
X266490D01*
G01X266720Y28490D02*
X267770D01*
G01X267700Y27780D02*
X267660Y27740D01*
G01X267700Y28420D02*
Y27780D01*
G01X267800Y28520D02*
X267700Y28420D01*
G01Y27880D02*
X266730D01*
G01Y28090D02*
X267700D01*
G01Y28290D02*
X266730D01*
G01X272060Y28990D02*
X266510D01*
G01X266550Y28680D02*
X272290D01*
G01X271400Y28520D02*
X267800D01*
G01X260700Y26220D02*
X266120Y31830D01*
G01X260670Y26190D02*
X260700Y26220D01*
G01X260680Y26170D02*
X260670Y26190D01*
G01X260990Y25900D02*
X260680Y26170D01*
G01X261020Y25890D02*
X260990Y25900D01*
G01X261040D02*
X261020Y25890D01*
G01X266160Y31200D02*
X261040Y25900D01*
G01X261120Y25990D02*
X260890D01*
G01X260770Y26090D02*
X261220D01*
G01X261320Y26180D02*
X260670D01*
G01X260760Y26290D02*
X261420D01*
G01X261510Y26380D02*
X260860D01*
G01X260950Y26490D02*
X261610D01*
G01X261700Y26590D02*
X261050D01*
G01X261140Y26680D02*
X261800D01*
G01X261900Y26790D02*
X261240D01*
G01X261340Y26880D02*
X261990D01*
G01X262090Y26990D02*
X261440D01*
G01X261530Y27090D02*
X262190D01*
G01X262280Y27180D02*
X261630D01*
G01X261730Y27290D02*
X262380D01*
G01X262480Y27380D02*
X261820D01*
G01X261920Y27490D02*
X262570D01*
G01X264240Y29880D02*
X264890D01*
G01X264990Y29990D02*
X264330D01*
G01X264430Y30090D02*
X265090D01*
G01X265180Y30180D02*
X264530D01*
G01X264620Y30290D02*
X265280D01*
G01X265470Y30490D02*
X264820D01*
G01X265010Y30680D02*
X265660D01*
G01X260370Y45100D02*
X260400Y45120D01*
G01X260370Y44560D02*
Y45100D01*
G01X260380Y44540D02*
X260370Y44560D01*
G01X260430Y44430D02*
X260380Y44540D01*
G01X260440Y44420D02*
X260430Y44430D01*
G01X265620Y38830D02*
X260440Y44420D01*
G01X260370Y45090D02*
X260430D01*
G01X260370Y44990D02*
X260520D01*
G01X260610Y44880D02*
X260370D01*
G01Y44790D02*
X260710D01*
G01X260800Y44680D02*
X260370D01*
G01Y44590D02*
X260890D01*
G01X260990Y44490D02*
X260400D01*
G01X260470Y44380D02*
X261080D01*
G01X261170Y44290D02*
X260560D01*
G01X260650Y44180D02*
X261260D01*
G01X261360Y44090D02*
X260750D01*
G01X260840Y43990D02*
X261450D01*
G01X261540Y43880D02*
X260930D01*
G01X261020Y43790D02*
X261640D01*
G01X261730Y43680D02*
X261120D01*
G01X261210Y43590D02*
X261820D01*
G01X261920Y43490D02*
X261300D01*
G01X261400Y43380D02*
X262010D01*
G01X262100Y43290D02*
X261490D01*
G01X261580Y43180D02*
X262200D01*
G01X262290Y43090D02*
X261680D01*
G01X261770Y42990D02*
X262380D01*
G01X262480Y42880D02*
X261860D01*
G01X261950Y42790D02*
X262570D01*
G01X262660Y42680D02*
X262050D01*
G01X262140Y42590D02*
X262750D01*
G01X262850Y42490D02*
X262230D01*
G01X262330Y42380D02*
X262940D01*
G01X263030Y42290D02*
X262420D01*
G01X262510Y42180D02*
X263120D01*
G01X263220Y42090D02*
X262610D01*
G01X262700Y41990D02*
X263310D01*
G01X263400Y41880D02*
X262790D01*
G01X262880Y41790D02*
X263500D01*
G01X263590Y41680D02*
X262980D01*
G01X263070Y41590D02*
X263680D01*
G01X263780Y41490D02*
X263160D01*
G01X263250Y41380D02*
X263870D01*
G01X263960Y41290D02*
X263350D01*
G01X263440Y41180D02*
X264060D01*
G01X264150Y41090D02*
X263530D01*
G01X263620Y40990D02*
X264240D01*
G01X264340Y40880D02*
X263720D01*
G01X263810Y40790D02*
X264430D01*
G01X264520Y40680D02*
X263900D01*
G01X263990Y40590D02*
X264620D01*
G01X264710Y40490D02*
X264090D01*
G01X264180Y40380D02*
X264800D01*
G01X264890Y40290D02*
X264270D01*
G01X264370Y40180D02*
X264990D01*
G01X265080Y40090D02*
X264460D01*
G01X264550Y39990D02*
X265170D01*
G01X265270Y39880D02*
X264650D01*
G01X264830Y39680D02*
X266070D01*
G01X266080Y39490D02*
X265020D01*
G01X264770Y41780D02*
X265280D01*
G01X264730Y41740D02*
X264770Y41780D01*
G01X264730Y41280D02*
Y41740D01*
G01X264770Y41240D02*
X264730Y41280D01*
G01Y41680D02*
X274980D01*
G01X274910Y41490D02*
X264730D01*
G01Y41290D02*
X274750D01*
G01X267380Y42590D02*
X265950D01*
G01X265370Y41850D02*
X265280Y41780D01*
G01X265390Y41900D02*
X265370Y41850D01*
G01X265390Y41910D02*
Y41900D01*
G01X265510Y42160D02*
X265390Y41910D01*
G01X265530Y42170D02*
X265510Y42160D01*
G01X265960Y42590D02*
X265530Y42170D01*
G01X265290Y41790D02*
X266020D01*
G01X266130Y42120D02*
X266240Y42190D01*
G01X265960Y41950D02*
X266130Y42120D01*
G01X265940Y41840D02*
X265960Y41950D01*
G01X266030Y41780D02*
X265940Y41840D01*
G01X266100Y42090D02*
X265480D01*
G01X265430Y41990D02*
X266000D01*
G01X265950Y41880D02*
X265380D01*
G01X265640Y42290D02*
X267320D01*
G01Y42490D02*
X265850D01*
G01X266200Y38890D02*
X269430Y35410D01*
G01X266190Y38890D02*
X266200D01*
G01X266150Y38940D02*
X266190Y38890D01*
G01X266120Y39000D02*
X266150Y38940D01*
G01X265940Y41130D02*
X266120Y39000D01*
G01X266040Y41240D02*
X265940Y41130D01*
G01X266460Y35090D02*
X265990D01*
G01X265980Y35290D02*
X266440D01*
G01X266420Y35490D02*
X265960D01*
G01X265940Y35680D02*
X266410D01*
G01X266390Y35880D02*
X265920D01*
G01X265900Y36090D02*
X266370D01*
G01X266360Y36290D02*
X265890D01*
G01X265870Y36490D02*
X266340D01*
G01X266320Y36680D02*
X265850D01*
G01X265840Y36880D02*
X266310D01*
G01X266290Y37090D02*
X265820D01*
G01X265800Y37290D02*
X266270D01*
G01X266250Y37490D02*
X265790D01*
G01X265770Y37680D02*
X266240D01*
G01X266220Y37880D02*
X265750D01*
G01X265740Y37990D02*
X266250D01*
G01X266750Y38290D02*
X265720D01*
G01X265700Y38490D02*
X266570D01*
G01X265640Y38800D02*
X265620Y38830D01*
G01X265680Y38700D02*
X265640Y38800D01*
G01X265680Y38690D02*
Y38700D01*
G01Y38680D02*
Y38690D01*
G01X266380Y38680D02*
X265680D01*
G01X265580Y38880D02*
X266200D01*
G01X266130Y38990D02*
X265480D01*
G01X265390Y39090D02*
X266120D01*
G01X266110Y39180D02*
X265300D01*
G01X265200Y39290D02*
X266100D01*
G01X266090Y39380D02*
X265110D01*
G01X264920Y39590D02*
X266070D01*
G01X266060Y39790D02*
X265580D01*
G01X265370Y41240D02*
X264770D01*
G01X265470Y41150D02*
X265370Y41240D01*
G01X265590Y39800D02*
X265470Y41150D01*
G01X265430Y41180D02*
X265990D01*
G01X265940Y41090D02*
X265480D01*
G01X265490Y40990D02*
X265960D01*
G01Y40880D02*
X265490D01*
G01X265500Y40790D02*
X265970D01*
G01X265980Y40680D02*
X265510D01*
G01X265520Y40590D02*
X265990D01*
G01X266000Y40490D02*
X265530D01*
G01X265540Y40380D02*
X266010D01*
G01Y40290D02*
X265550D01*
G01Y40180D02*
X266020D01*
G01X266030Y40090D02*
X265570D01*
G01Y39990D02*
X266040D01*
G01X266050Y39880D02*
X265580D01*
G01X265420Y39730D02*
X260400Y45120D01*
G01X265530Y39700D02*
X265420Y39730D01*
G01X265590Y39800D02*
X265530Y39700D01*
G01X264740Y39790D02*
X265360D01*
G01X265680Y38680D02*
X266120Y33530D01*
G01X266130Y33490D02*
X266600D01*
G01X266610Y33290D02*
X266140D01*
G01X266160Y33090D02*
X266630D01*
G01X266650Y32880D02*
X266180D01*
G01X266200Y32680D02*
X266670D01*
G01X266710Y32590D02*
X266210D01*
G01X266220Y31940D02*
X266120Y31830D01*
G01X266250Y32010D02*
X266220Y31940D01*
G01X266070Y31790D02*
X266760D01*
G01Y31590D02*
X265880D01*
G01X265690Y31380D02*
X266780D01*
G01X266140Y31180D02*
X265490D01*
G01X265400Y31090D02*
X266050D01*
G01X265950Y30990D02*
X265300D01*
G01X265200Y30880D02*
X265860D01*
G01X265760Y30790D02*
X265110D01*
G01X264920Y30590D02*
X265570D01*
G01X265370Y30380D02*
X264720D01*
G01X266100Y33790D02*
X266570D01*
G01X266550Y33990D02*
X266090D01*
G01X266070Y34180D02*
X266540D01*
G01X266520Y34380D02*
X266050D01*
G01X266030Y34590D02*
X266500D01*
G01X266490Y34790D02*
X266020D01*
G01X266010Y34880D02*
X266480D01*
G01X266470Y34990D02*
X266000D01*
G01X265980Y35180D02*
X266450D01*
G01X266440Y35380D02*
X265970D01*
G01X265950Y35590D02*
X266420D01*
G01X266400Y35790D02*
X265930D01*
G01X265920Y35990D02*
X266380D01*
G01X266360Y36180D02*
X265900D01*
G01X265880Y36380D02*
X266350D01*
G01X266330Y36590D02*
X265860D01*
G01X265850Y36790D02*
X266310D01*
G01X266300Y36990D02*
X265830D01*
G01X265810Y37180D02*
X266280D01*
G01X266260Y37380D02*
X265790D01*
G01X265780Y37590D02*
X266240D01*
G01X266230Y37790D02*
X265760D01*
G01X266390Y38010D02*
X269120Y35070D01*
G01X266270Y38030D02*
X266390Y38010D01*
G01X266220Y37930D02*
X266270Y38030D01*
G01X266490Y34680D02*
X266030D01*
G01X266040Y34490D02*
X266510D01*
G01X266530Y34290D02*
X266060D01*
G01X266080Y34090D02*
X266550D01*
G01X266560Y33880D02*
X266090D01*
G01X266110Y33680D02*
X266580D01*
G01X266590Y33590D02*
X266120D01*
G01X266250Y32070D02*
Y32010D01*
G01X266120Y33530D02*
X266250Y32070D01*
G01X266240Y31990D02*
X266920D01*
G01X266770Y31810D02*
X266750Y31740D01*
G01X266820Y31890D02*
X266770Y31810D01*
G01X266750Y31680D02*
X265980D01*
G01X265790Y31490D02*
X266770D01*
G01X266790Y31180D02*
X266290D01*
G01X266260Y31220D02*
X266160Y31200D01*
G01X266260Y31220D02*
X266330Y31140D01*
G01X266430Y29990D02*
X266900D01*
G01X266880Y30180D02*
X266410D01*
G01X266390Y30380D02*
X266860D01*
G01X266850Y30590D02*
X266380D01*
G01X266360Y30790D02*
X266830D01*
G01X266810Y30990D02*
X266350D01*
G01X266240Y32180D02*
X267110D01*
G01X267300Y32380D02*
X266220D01*
G01X266190Y32790D02*
X266660D01*
G01X266670Y32640D02*
X266220Y37930D01*
G01X266410Y37990D02*
X267030D01*
G01X267220Y37790D02*
X266600D01*
G01X266780Y37590D02*
X267400D01*
G01X266660Y38380D02*
X265710D01*
G01X265690Y38590D02*
X266480D01*
G01X266290Y38790D02*
X265650D01*
G01X266350Y42200D02*
X266240Y42190D01*
G01X266400Y42110D02*
X266350Y42200D01*
G01X266400Y41880D02*
Y42110D01*
G01X266300Y41780D02*
X266400Y41880D01*
G01X266030Y41780D02*
X266300D01*
G01X266230Y42180D02*
X265540D01*
G01X266410Y43170D02*
X266440Y43190D01*
G01X266400Y43140D02*
X266410Y43170D01*
G01X266400Y42940D02*
Y43140D01*
G01X266390Y42900D02*
X266400Y42940D01*
G01X266370Y42850D02*
X266390Y42900D01*
G01X266320Y42790D02*
X266370Y42850D01*
G01X266230Y42750D02*
X266320Y42790D01*
G01X265960Y42590D02*
X266230Y42750D01*
G01X266440Y43180D02*
X267270D01*
G01X266400Y42990D02*
X269290D01*
G01X269280Y42790D02*
X266300D01*
G01X266350Y42180D02*
X267320D01*
G01Y41990D02*
X266400D01*
G01X266310Y41790D02*
X267420D01*
G01X266610Y33380D02*
X266140D01*
G01X266150Y33180D02*
X266620D01*
G01X266640Y32990D02*
X266170D01*
G01X266740Y32550D02*
X266840Y32580D01*
G01X266670Y32640D02*
X266740Y32550D01*
G01X266820Y31880D02*
X266170D01*
G01X266250Y32090D02*
X267010D01*
G01X266830Y31890D02*
X266820D01*
G01X266830Y31900D02*
Y31890D01*
G01Y31900D02*
X269420Y34590D01*
G01X269230Y34380D02*
X268590D01*
G01X268390Y34180D02*
X269040D01*
G01X268850Y33990D02*
X268200D01*
G01X268010Y33790D02*
X268650D01*
G01X268560Y33680D02*
X267910D01*
G01X267960Y33740D02*
X266840Y32580D01*
G01X266850Y32590D02*
X267490D01*
G01X267400Y32490D02*
X266220D01*
G01X266230Y32290D02*
X267210D01*
G01X266950Y32680D02*
X267590D01*
G01X267690Y32790D02*
X267050D01*
G01X267140Y32880D02*
X267790D01*
G01X267880Y32990D02*
X267240D01*
G01X267330Y33090D02*
X267980D01*
G01X268070Y33180D02*
X267430D01*
G01X267530Y33290D02*
X268170D01*
G01X268270Y33380D02*
X267620D01*
G01X267720Y33490D02*
X268360D01*
G01X268460Y33590D02*
X267810D01*
G01X268640Y35590D02*
X269270D01*
G01X269080Y35790D02*
X268460D01*
G01X268270Y35990D02*
X268890D01*
G01X268710Y36180D02*
X268080D01*
G01X267990Y36290D02*
X268610D01*
G01X268520Y36380D02*
X267900D01*
G01X267810Y36490D02*
X268430D01*
G01X268330Y36590D02*
X267710D01*
G01X267620Y36680D02*
X268240D01*
G01X268150Y36790D02*
X267530D01*
G01X267430Y36880D02*
X268060D01*
G01X267960Y36990D02*
X267340D01*
G01X267250Y37090D02*
X267870D01*
G01X267780Y37180D02*
X267150D01*
G01X267060Y37290D02*
X267680D01*
G01X267590Y37380D02*
X266970D01*
G01X266880Y37490D02*
X267500D01*
G01X267310Y37680D02*
X266690D01*
G01X266500Y37880D02*
X267120D01*
G01X266940Y38090D02*
X265740D01*
G01X265730Y38180D02*
X266850D01*
G01X268700Y37460D02*
X268740Y37420D01*
G01X267320Y41880D02*
X266400D01*
G01X267420Y41780D02*
X267320Y41880D01*
G01X266400Y42090D02*
X267320D01*
G01X268650Y42790D02*
X268760Y42680D01*
G01X268380Y42760D02*
X268650Y42790D01*
G01X268100Y42730D02*
X268380Y42760D01*
G01X267980Y42720D02*
X268100Y42730D01*
G01X267880Y42700D02*
X267980Y42720D01*
G01X267630Y42660D02*
X267880Y42700D01*
G01X267620Y42660D02*
X267630D01*
G01X267530Y42640D02*
X267620Y42660D01*
G01X267520Y42640D02*
X267530D01*
G01X267400Y42620D02*
X267520Y42640D01*
G01X267320Y42520D02*
X267400Y42620D01*
G01X267320Y41880D02*
Y42520D01*
G01X267260Y43190D02*
X266440D01*
G01X267280Y43180D02*
X267260Y43190D01*
G01X267310Y43170D02*
X267280Y43180D01*
G01X267340Y43150D02*
X267310Y43170D01*
G01X267420Y43130D02*
X267340Y43150D01*
G01X267440Y43140D02*
X267420Y43130D01*
G01X267680Y43180D02*
X267440Y43140D01*
G01X268180Y43250D02*
X267680Y43180D01*
G01X268300Y43260D02*
X268180Y43250D01*
G01X268360Y43260D02*
X268300D01*
G01X268520Y43280D02*
X268360Y43260D01*
G01X268660Y43290D02*
X268520Y43280D01*
G01X266120Y42680D02*
X267770D01*
G01X267320Y42380D02*
X265750D01*
G01X267420Y41780D02*
X273260D01*
G01X271330Y43290D02*
X268640D01*
G01X268660D02*
X268760Y43390D01*
G01X266790Y31290D02*
X265590D01*
G01X266330Y31090D02*
X266800D01*
G01X266820Y30880D02*
X266350D01*
G01X266370Y30680D02*
X266840D01*
G01X266850Y30490D02*
X266380D01*
G01X266400Y30290D02*
X266870D01*
G01X266890Y30090D02*
X266420D01*
G01X266440Y29880D02*
X266900D01*
G01X269880Y34920D02*
Y35060D01*
G01X272580Y32020D02*
X269880Y34920D01*
G01X269900Y35090D02*
X269110D01*
G01X269120Y34930D02*
X267960Y33740D01*
G01X269120Y35070D02*
Y34930D01*
G01X268110Y33880D02*
X268750D01*
G01X268940Y34090D02*
X268300D01*
G01X268490Y34290D02*
X269140D01*
G01X269330Y34490D02*
X268680D01*
G01X269570Y34590D02*
X271250Y32770D01*
G01X269420Y34590D02*
X269570D01*
G01X268780D02*
X269420D01*
G01X271310Y33380D02*
X270680D01*
G01X270590Y33490D02*
X271220D01*
G01X271120Y33590D02*
X270490D01*
G01X270400Y33680D02*
X271030D01*
G01X270940Y33790D02*
X270310D01*
G01X270220Y33880D02*
X270850D01*
G01X270750Y33990D02*
X270120D01*
G01X270030Y34090D02*
X270660D01*
G01X270570Y34180D02*
X269940D01*
G01X269850Y34290D02*
X270480D01*
G01X270380Y34380D02*
X269750D01*
G01X269660Y34490D02*
X270290D01*
G01X270200Y34590D02*
X269550D01*
G01X269920Y34880D02*
X269070D01*
G01X269120Y34990D02*
X269880D01*
G01X270000Y35180D02*
X269010D01*
G01X268920Y35290D02*
X270100D01*
G01X270200Y35380D02*
X268830D01*
G01X268740Y35490D02*
X269360D01*
G01X269570Y35410D02*
X271000Y36880D01*
G01X269430Y35410D02*
X269570D01*
G01X271350Y36590D02*
X270710D01*
G01X270620Y36490D02*
X271250D01*
G01X271160Y36380D02*
X270520D01*
G01X270420Y36290D02*
X271060D01*
G01X270970Y36180D02*
X270330D01*
G01X270230Y36090D02*
X270870D01*
G01X270770Y35990D02*
X270130D01*
G01X270040Y35880D02*
X270680D01*
G01X270580Y35790D02*
X269940D01*
G01X269850Y35680D02*
X270480D01*
G01X270390Y35590D02*
X269750D01*
G01X269650Y35490D02*
X270290D01*
G01X270010Y34790D02*
X268980D01*
G01X268880Y34680D02*
X270100D01*
G01X269170Y35680D02*
X268550D01*
G01X268360Y35880D02*
X268990D01*
G01X268800Y36090D02*
X268180D01*
G01X268790Y37420D02*
X271280D01*
G01X268740D02*
X268790D01*
G01X272220Y37490D02*
X268700D01*
G01X268740Y38450D02*
X268790D01*
G01X268700Y38410D02*
X268740Y38450D01*
G01X268700Y37460D02*
Y38410D01*
G01Y38290D02*
X271960D01*
G01X271990Y38090D02*
X268700D01*
G01Y37880D02*
X272610D01*
G01X272410Y37680D02*
X268700D01*
G01X268760Y42340D02*
Y42680D01*
G01X268800Y42290D02*
X268760Y42340D01*
G01X268750Y42680D02*
X271380D01*
G01X271250Y42290D02*
X268800D01*
G01X268760Y42380D02*
X271300D01*
G01Y42490D02*
X268760D01*
G01Y42590D02*
X271300D01*
G01X270750Y43000D02*
X270850Y42900D01*
G01X269310Y43000D02*
X270750D01*
G01X269210Y42900D02*
X269310Y43000D01*
G01X269210Y42860D02*
Y42900D01*
G01X269310Y42750D02*
X269210Y42860D01*
G01X270750Y42750D02*
X269310D01*
G01X270850Y42860D02*
X270750Y42750D01*
G01X268760Y43420D02*
Y43390D01*
G01X268800Y43460D02*
X268760Y43420D01*
G01X271250Y43460D02*
X268800D01*
G01X268750Y43380D02*
X271300D01*
G01X269210Y42880D02*
X266380D01*
G01X266400Y43090D02*
X272160D01*
G01X271610Y43180D02*
X267740D01*
G01X271910Y38450D02*
X268790D01*
G01X268700Y38380D02*
X271960D01*
G01Y38180D02*
X268700D01*
G01X272700Y37990D02*
X268700D01*
G01Y37790D02*
X272510D01*
G01X272310Y37590D02*
X268700D01*
G01X273090Y38390D02*
X269880Y35060D01*
G01X273390Y41240D02*
X266040D01*
G01X274840Y41380D02*
X264730D01*
G01Y41590D02*
X274940D01*
G01X271270Y29470D02*
Y29480D01*
G01X271260Y29400D02*
X271270Y29470D01*
G01X271260Y29140D02*
Y29400D01*
G01X271270Y29120D02*
X271260Y29140D01*
G01X271170Y29000D02*
X271270Y29120D01*
G01Y29490D02*
X272040D01*
G01X272000Y29290D02*
X271260D01*
G01X271240Y29090D02*
X272040D01*
G01X271310Y29660D02*
X271270Y29480D01*
G01X271310Y29670D02*
Y29660D01*
G01X271420Y29980D02*
X271310Y29670D01*
G01X271260Y29380D02*
X272020D01*
G01X272050Y29010D02*
X272060Y28990D01*
G01X272000Y29270D02*
X272050Y29010D01*
G01X272000Y29280D02*
Y29270D01*
G01Y29300D02*
Y29280D01*
G01X272210Y28750D02*
X272150Y28840D01*
G01X272220Y28740D02*
X272210Y28750D01*
G01X272230Y28730D02*
X272220Y28740D01*
G01X272070Y28980D02*
X272060Y28990D01*
G01X272150Y28850D02*
X272070Y28980D01*
G01X272020Y29180D02*
X271260D01*
G01X271290Y29590D02*
X272060D01*
G01X272050Y29560D02*
X272000Y29300D01*
G01X272060Y29580D02*
X272050Y29560D01*
G01X272280Y29310D02*
X272290Y29330D01*
G01X272230Y29840D02*
X272450Y30000D01*
G01X272220Y29830D02*
X272230Y29840D01*
G01X272210Y29810D02*
X272220Y29830D01*
G01X272070Y29600D02*
X272210Y29810D01*
G01X272060Y29580D02*
X272070Y29600D01*
G01X271350Y29790D02*
X272190D01*
G01X272120Y29680D02*
X271310D01*
G01X272150Y28790D02*
X272190D01*
G01X272230Y28730D02*
X272450Y28570D01*
G01X272020Y27990D02*
X273570D01*
G01X273730Y28090D02*
X271840D01*
G01X271480Y28490D02*
X271400Y28520D01*
G01X271490Y28480D02*
X271480Y28490D01*
G01X271490Y28470D02*
Y28480D01*
G01X271530Y28400D02*
X271490Y28470D01*
G01X271540Y28400D02*
X271530D01*
G01X271550Y28390D02*
X271540Y28400D01*
G01X271620Y28290D02*
X271550Y28390D01*
G01X271630Y28280D02*
X271620Y28290D01*
G01X271860Y28060D02*
X271630Y28280D01*
G01Y28290D02*
X273970D01*
G01X271880Y28050D02*
X271860Y28060D01*
G01X272680Y27750D02*
X273020Y27760D01*
G01X272670Y27750D02*
X272680D01*
G01X272660D02*
X272670D01*
G01X272500Y27770D02*
X272660Y27750D01*
G01X272480Y27770D02*
X272500D01*
G01X271880Y28050D02*
X272480Y27770D01*
G01X273130Y27790D02*
X272460D01*
G01Y28560D02*
X272450Y28570D01*
G01X272480Y28560D02*
X272460D01*
G01X272650Y28500D02*
X272480Y28560D01*
G01X272870Y28490D02*
X272890D01*
G01X272740D02*
X272870D01*
G01X272670Y28500D02*
X272740Y28490D01*
G01X272650Y28500D02*
X272670D01*
G01X272310Y29120D02*
X272280Y29310D01*
G01X272320Y29090D02*
X272310Y29120D01*
G01X272490Y28870D02*
X272320Y29090D01*
G01X272510Y28860D02*
X272490Y28870D01*
G01X272680Y28780D02*
X272510Y28860D01*
G01X272690Y28780D02*
X272680D01*
G01X272730Y28770D02*
X272690Y28780D01*
G01X272790Y28770D02*
X272730D01*
G01X272810D02*
X272790D01*
G01X272840Y29800D02*
X272850D01*
G01X272750D02*
X272840D01*
G01X272730Y29790D02*
X272750Y29800D01*
G01X272420Y29630D02*
X272730Y29790D01*
G01X272400Y29610D02*
X272420Y29630D01*
G01X272290Y29330D02*
X272400Y29610D01*
G01X272340Y29470D02*
X273280D01*
G01X273300Y29270D02*
X272290D01*
G01X272340Y29070D02*
X273250D01*
G01X273070Y28870D02*
X272500D01*
G01X272810Y28770D02*
X272940Y28790D01*
G01X273140Y29660D02*
X272490D01*
G01X273130Y30010D02*
X273440Y29750D01*
G01X273210Y29570D02*
X272380D01*
G01X272300Y29370D02*
X273290D01*
G01X273100Y29700D02*
X272850Y29800D01*
G01X273120Y29690D02*
X273100Y29700D01*
G01X273270Y29490D02*
X273120Y29690D01*
G01X273280Y29460D02*
X273270Y29490D01*
G01X272940Y29770D02*
X272670D01*
G01X272960Y28790D02*
X272940D01*
G01X273180Y28930D02*
X272960Y28790D01*
G01X273190Y28950D02*
X273180Y28930D01*
G01X273300Y29180D02*
X273190Y28950D01*
G01X273310Y29200D02*
X273300Y29180D01*
G01X273280Y29460D02*
X273310Y29200D01*
G01X273150Y28590D02*
X274170D01*
G01X273030Y27760D02*
X273020D01*
G01X273320Y27830D02*
X273030Y27760D01*
G01X273330Y27840D02*
X273320Y27830D01*
G01X273840Y28150D02*
X273330Y27840D01*
G01X273090Y28540D02*
X273130Y28560D01*
G01X272890Y28490D02*
X273090Y28540D01*
G01X273200Y28970D02*
X272420D01*
G01X272300Y29160D02*
X273300D01*
G01X271480Y28490D02*
X274110D01*
G01X273930Y28240D02*
X273840Y28150D01*
G01X273990Y28310D02*
X273930Y28240D01*
G01X274120Y28500D02*
X273990Y28310D01*
G01X273880Y28180D02*
X271730D01*
G01X271550Y28380D02*
X274040D01*
G01X274240Y28750D02*
X274300Y28920D01*
G01X274200Y28650D02*
X274240Y28750D01*
G01X274200Y28640D02*
Y28650D01*
G01X274130Y28510D02*
X274200Y28640D01*
G01X274120Y28500D02*
X274130Y28510D01*
G01X274290Y28880D02*
X273475D01*
G01X273480D02*
X273540D01*
G01X273440Y28820D02*
X273130Y28560D01*
G01X273470Y28870D02*
X273440Y28820D01*
G01X273270Y28680D02*
X274220D01*
G01X274250Y28790D02*
X273460D01*
G01X274220D02*
X274250D01*
G01X273470Y29700D02*
X273440Y29750D01*
G01X273590Y29310D02*
X273470Y29700D01*
G01X273590Y29250D02*
Y29310D01*
G01X273470Y28870D02*
X273590Y29250D01*
G01X273400Y29790D02*
X274660D01*
G01X274850Y29590D02*
X273510D01*
G01X273570Y29380D02*
X275030D01*
G01X274330Y29180D02*
X273570D01*
G01X273510Y28990D02*
X274310D01*
G01X273400Y27880D02*
X272240D01*
G01X274750Y29680D02*
X273480D01*
G01X273530Y29490D02*
X274940D01*
G01X275130Y29290D02*
X274440D01*
G01X274300Y28940D02*
Y28920D01*
G01X274340Y29210D02*
X274300Y28940D01*
G01X274400Y29290D02*
X274340Y29210D01*
G01X274320Y29090D02*
X273540D01*
G01X274400Y29290D02*
X274510Y29270D01*
G01X273590Y29290D02*
X274400D01*
G01X274590Y29180D02*
X275220D01*
G01X275310Y29090D02*
X274680D01*
G01X274770Y28990D02*
X275410D01*
G01X275460Y28880D02*
X275500D01*
G01X275510D02*
X274870D01*
G01X274960Y28790D02*
X275595D01*
G01X275590D02*
X275540D01*
G01X275695Y28680D02*
X275050D01*
G01X275140Y28590D02*
X275780D01*
G01X275870Y28490D02*
X275235D01*
G01X275335Y28380D02*
X275970D01*
G01X276060Y28290D02*
X275420D01*
G01X275525Y28180D02*
X276150D01*
G01X276250Y28090D02*
X275610D01*
G01X275700Y27990D02*
X276340D01*
G01X276430Y27880D02*
X275790D01*
G01X275880Y27790D02*
X276530D01*
G01X276710Y27590D02*
X276070D01*
G01X275980Y27680D02*
X276620D01*
G01X276800Y27490D02*
X276160D01*
G01X276260Y27380D02*
X276900D01*
G01X276990Y27290D02*
X276350D01*
G01X276440Y27180D02*
X277080D01*
G01X277180Y27090D02*
X276530D01*
G01X276630Y26990D02*
X277270D01*
G01X277360Y26880D02*
X276720D01*
G01X276810Y26790D02*
X277460D01*
G01X277550Y26680D02*
X276910D01*
G01X277000Y26590D02*
X277640D01*
G01X277830Y26380D02*
X277190D01*
G01X277370Y26180D02*
X277980D01*
G01X277970Y26240D02*
X274160Y30330D01*
G01X277640Y25900D02*
X277660Y25880D01*
G01X274510Y29270D02*
X277640Y25900D01*
G01X277560Y25990D02*
X277780D01*
G01X277740Y26490D02*
X277090D01*
G01X277280Y26290D02*
X277920D01*
G01X277690Y25900D02*
X277660Y25880D01*
G01X277980Y26190D02*
X277690Y25900D01*
G01X277990Y26210D02*
X277980Y26190D01*
G01Y26220D02*
X277990Y26210D01*
G01X277970Y26240D02*
X277980Y26220D01*
G01X277460Y26090D02*
X277880D01*
G01X271240Y32790D02*
X271870D01*
G01X271680Y32990D02*
X271050D01*
G01X270870Y33180D02*
X271500D01*
G01X270900Y36790D02*
X271540D01*
G01X271290Y37180D02*
X271930D01*
G01X271740Y36990D02*
X271100D01*
G01X271300Y42340D02*
X271250Y42290D01*
G01X271300Y42620D02*
Y42340D01*
G01X270850Y42900D02*
Y42860D01*
G01Y42880D02*
X272820D01*
G01X272530Y42990D02*
X270760D01*
G01X271300Y43420D02*
X271250Y43460D01*
G01X271300Y43320D02*
Y43420D01*
G01X271380Y43220D02*
X271300Y43320D01*
G01X271430Y43220D02*
X271380D01*
G01X271990Y43130D02*
X271430Y43220D01*
G01X272170Y43090D02*
X271990Y43130D01*
G01X271810Y42650D02*
X272220Y42560D01*
G01X271520Y42700D02*
X271810Y42650D01*
G01X271490Y42700D02*
X271520D01*
G01X271410Y42720D02*
X271490Y42700D01*
G01X271300Y42620D02*
X271410Y42720D01*
G01X271600Y42680D02*
X273190D01*
G01X271950Y38410D02*
X271910Y38450D01*
G01X272130Y38060D02*
X272330Y38260D01*
G01X272020Y38030D02*
X272130Y38060D01*
G01X271960Y38130D02*
X272020Y38030D01*
G01X271960Y38310D02*
Y38130D01*
G01Y38320D02*
Y38310D01*
G01X271950Y38410D02*
X271960Y38320D01*
G01X272160Y38090D02*
X272800D01*
G01X270810Y36680D02*
X271450D01*
G01X271370Y37360D02*
X271280Y37420D01*
G01X271350Y37250D02*
X271370Y37360D01*
G01X271000Y36880D02*
X271350Y37250D01*
G01X271640Y36880D02*
X271000D01*
G01X271330Y37380D02*
X272120D01*
G01X272030Y37290D02*
X271360D01*
G01X271200Y37090D02*
X271830D01*
G01X271400Y33290D02*
X270770D01*
G01X270960Y33090D02*
X271590D01*
G01X271770Y32880D02*
X271140D01*
G01X271330Y32680D02*
X271960D01*
G01X272050Y32590D02*
X271420D01*
G01X271510Y32490D02*
X272150D01*
G01X272240Y32380D02*
X271610D01*
G01X271700Y32290D02*
X272330D01*
G01X272520Y32090D02*
X271890D01*
G01X272070Y31880D02*
X273210D01*
G01X273200Y31790D02*
X272170D01*
G01X271430Y29990D02*
X271420Y29980D01*
G01X271640Y30300D02*
X271430Y29990D01*
G01X271650Y30310D02*
X271640Y30300D01*
G01X271890Y30530D02*
X271650Y30310D01*
G01X271900Y30530D02*
X271890D01*
G01X272020Y30610D02*
X271900Y30530D01*
G01X272030Y30620D02*
X272020Y30610D01*
G01X272090Y30650D02*
X272030Y30620D01*
G01X272250Y30720D02*
X272090Y30650D01*
G01X272290Y29880D02*
X271390D01*
G01X271490Y30090D02*
X272750D01*
G01X272160Y30680D02*
X273830D01*
G01X273920Y30590D02*
X271980D01*
G01X271740Y30380D02*
X274110D01*
G01X274290Y30180D02*
X271570D01*
G01X272460Y30010D02*
X272450Y30000D01*
G01X272480Y30010D02*
X272460D01*
G01X272650Y30070D02*
X272480Y30010D01*
G01X272670Y30070D02*
X272650D01*
G01X272740Y30080D02*
X272670Y30070D01*
G01X272760Y30090D02*
X272740Y30080D01*
G01X272820Y30090D02*
X272760D01*
G01X272850Y30080D02*
X272820Y30090D01*
G01X272430Y29990D02*
X271430D01*
G01X272890Y30080D02*
X273090Y30030D01*
G01X272850Y30080D02*
X272890D01*
G01X272340Y30750D02*
X272250Y30720D01*
G01X272350Y30760D02*
X272340Y30750D01*
G01X272490Y30790D02*
X272350Y30760D01*
G01X272570Y30810D02*
X272490Y30790D01*
G01X272350Y31590D02*
X271250Y32770D01*
G01X272610Y31310D02*
X272350Y31590D01*
G01X272640Y31260D02*
X272610Y31310D01*
G01X272670Y31110D02*
X272640Y31260D01*
G01X272680Y31090D02*
X272670Y31110D01*
G01X272680Y31070D02*
Y31090D01*
G01X272660Y30900D02*
X272680Y31070D01*
G01X272660Y30890D02*
Y30900D01*
G01X272570Y30810D02*
X272660Y30890D01*
G01X271790Y32180D02*
X272430D01*
G01X272750Y32080D02*
X273260Y38310D01*
G01X272690Y32000D02*
X272750Y32080D01*
G01X272580Y32020D02*
X272690Y32000D01*
G01X272350Y38290D02*
X272330Y38260D01*
G01X272990Y38290D02*
X272350D01*
G01D02*
X273160Y39130D01*
G01X272740Y38680D02*
X275000D01*
G01Y38490D02*
X272550D01*
G01X272250Y38180D02*
X272890D01*
G01X272920Y34090D02*
X273380D01*
G01X273370Y33880D02*
X272900D01*
G01X272880Y33680D02*
X273350D01*
G01X273340Y33490D02*
X272870D01*
G01X272850Y33290D02*
X273320D01*
G01X273310Y33090D02*
X272840D01*
G01X272820Y32880D02*
X273290D01*
G01X273270Y32680D02*
X272810D01*
G01X272790Y32490D02*
X273250D01*
G01X273240Y32290D02*
X272770D01*
G01X272750Y32090D02*
X273220D01*
G01X273180Y31590D02*
X272350D01*
G01X272540Y31380D02*
X273180D01*
G01X273360Y31180D02*
X272660D01*
G01X272670Y30990D02*
X273550D01*
G01X272500Y42480D02*
X272220Y42560D01*
G01X272510Y42470D02*
X272500Y42480D01*
G01X272620Y42440D02*
X272510Y42470D01*
G01X272620Y42430D02*
Y42440D01*
G01X272730Y42390D02*
X272620Y42430D01*
G01X272740Y42380D02*
X272730Y42390D01*
G01X273600Y42380D02*
X272740D01*
G01X272460Y42490D02*
X273490D01*
G01X272290Y43050D02*
X272170Y43090D01*
G01X272400Y43030D02*
X272290Y43050D01*
G01X272640Y42950D02*
X272400Y43030D01*
G01X272750Y42910D02*
X272640Y42950D01*
G01X272810Y42890D02*
X272750Y42910D01*
G01X272100Y42590D02*
X273350D01*
G01X273030Y42790D02*
X270780D01*
G01X273350Y41830D02*
X273260Y41780D01*
G01X273340Y41930D02*
X273350Y41830D01*
G01X273270Y42040D02*
X273340Y41930D01*
G01X273250Y42060D02*
X273270Y42040D01*
G01X272950Y42280D02*
X273250Y42060D01*
G01X272940Y42290D02*
X272950Y42280D01*
G01X272930Y42290D02*
X272940D01*
G01X272740Y42380D02*
X272930Y42290D01*
G01X273270Y41790D02*
X274990D01*
G01X274970Y41990D02*
X273310D01*
G01X273080Y42180D02*
X274890D01*
G01X275000Y40180D02*
X273220D01*
G01X273190Y39160D02*
X273160Y39130D01*
G01X273220Y39220D02*
X273190Y39160D01*
G01X273220Y40240D02*
Y39220D01*
G01X273120Y39090D02*
X273790D01*
G01X273960Y39290D02*
X273220D01*
G01Y39490D02*
X274150D01*
G01X274340Y39680D02*
X273220D01*
G01Y39790D02*
X275000D01*
G01Y39990D02*
X273220D01*
G01X273330Y40320D02*
X273430Y40420D01*
G01X273260Y40320D02*
X273330D01*
G01X273220Y40280D02*
X273260Y40320D01*
G01X273220Y40240D02*
Y40280D01*
G01X272930Y38880D02*
X275000D01*
G01X273720Y38180D02*
X273250D01*
G01X273200Y38410D02*
X273090Y38390D01*
G01X273260Y38310D02*
X273200Y38410D01*
G01X272980Y34880D02*
X273450D01*
G01X273460Y34990D02*
X272990D01*
G01X273010Y35180D02*
X273480D01*
G01X273490Y35380D02*
X273030D01*
G01X273040Y35590D02*
X273510D01*
G01X273520Y35790D02*
X273060D01*
G01X273070Y35990D02*
X273540D01*
G01X273560Y36180D02*
X273090D01*
G01X273110Y36380D02*
X273570D01*
G01X273590Y36590D02*
X273120D01*
G01X273140Y36790D02*
X273610D01*
G01X273620Y36990D02*
X273160D01*
G01X273170Y37180D02*
X273640D01*
G01X273650Y37380D02*
X273190D01*
G01X273200Y37590D02*
X273670D01*
G01X273690Y37790D02*
X273220D01*
G01X273240Y37990D02*
X273700D01*
G01X273090Y38380D02*
X272450D01*
G01X272970Y34680D02*
X273440D01*
G01X273420Y34490D02*
X272950D01*
G01X272940Y34290D02*
X273400D01*
G01X273390Y34180D02*
X272930D01*
G01X272910Y33990D02*
X273380D01*
G01X273360Y33790D02*
X272890D01*
G01X272880Y33590D02*
X273350D01*
G01X273330Y33380D02*
X272860D01*
G01X272850Y33180D02*
X273310D01*
G01X273300Y32990D02*
X272830D01*
G01X272810Y32790D02*
X273280D01*
G01X273260Y32590D02*
X272800D01*
G01X272780Y32380D02*
X273250D01*
G01X273230Y32180D02*
X272760D01*
G01X273220Y31990D02*
X271980D01*
G01X272260Y31680D02*
X273190D01*
G01X273180Y31490D02*
X272450D01*
G01X272620Y31290D02*
X273260D01*
G01X273200Y31350D02*
X274160Y30330D01*
G01X274480Y29990D02*
X273150D01*
G01X273130Y30010D02*
X273090Y30030D01*
G01X273190Y31370D02*
X273170Y31440D01*
G01X273200Y31360D02*
X273190Y31370D01*
G01X273200Y31350D02*
Y31360D01*
G01X272960Y42830D02*
X272810Y42890D01*
G01X272970Y42820D02*
X272960Y42830D01*
G01X274220Y42540D02*
X274280Y42550D01*
G01X274210Y42540D02*
X274220D01*
G01X274100Y42510D02*
X274210Y42540D01*
G01X274090Y42510D02*
X274100D01*
G01X273960Y42460D02*
X274090Y42510D01*
G01X273960Y42450D02*
Y42460D01*
G01X273900Y42420D02*
X273960Y42450D01*
G01X273880Y42400D02*
X273900Y42420D01*
G01X273820Y42350D02*
X273880Y42400D01*
G01X273800Y42330D02*
X273820Y42350D01*
G01X273660Y42330D02*
X273800D01*
G01X273480Y42500D02*
X273660Y42330D01*
G01X273470Y42510D02*
X273480Y42500D01*
G01X272970Y42820D02*
X273470Y42510D01*
G01X274030Y42490D02*
X274550D01*
G01X274600Y41180D02*
X273440D01*
G01X273490Y41130D02*
X273430Y40420D01*
G01X273400Y40380D02*
X273950D01*
G01X274240Y41110D02*
X274270Y41100D01*
G01X274160Y41120D02*
X274240Y41110D01*
G01X274090Y41140D02*
X274160Y41120D01*
G01X274080Y41140D02*
X274090D01*
G01X273950Y41050D02*
X274080Y41140D01*
G01X273900Y40440D02*
X273950Y41050D01*
G01X274000Y40330D02*
X273900Y40440D01*
G01X274000Y41090D02*
X273490D01*
G01Y41130D02*
X273390Y41240D01*
G01X273030Y38990D02*
X273850D01*
G01X273820Y39140D02*
X274370Y39720D01*
G01X273790Y39090D02*
X273820Y39140D01*
G01X273790Y39050D02*
Y39090D01*
G01X273890Y38940D02*
X273790Y39050D01*
G01X274250Y39590D02*
X273220D01*
G01Y39380D02*
X274050D01*
G01X273860Y39180D02*
X273200D01*
G01X273220Y38380D02*
X273750D01*
G01X273740Y38370D02*
X273170Y31440D01*
G01X273450Y31090D02*
X272680D01*
G01X272650Y30880D02*
X273640D01*
G01X273730Y30790D02*
X272460D01*
G01X271850Y30490D02*
X274010D01*
G01X274200Y30290D02*
X271630D01*
G01X272940Y34380D02*
X273410D01*
G01X273430Y34590D02*
X272960D01*
G01X272980Y34790D02*
X273440D01*
G01X273470Y35090D02*
X273000D01*
G01X273010Y35290D02*
X273480D01*
G01X273500Y35490D02*
X273030D01*
G01X273050Y35680D02*
X273510D01*
G01X273530Y35880D02*
X273070D01*
G01X273080Y36090D02*
X273550D01*
G01X273570Y36290D02*
X273100D01*
G01X273110Y36490D02*
X273580D01*
G01X273600Y36680D02*
X273130D01*
G01X273150Y36880D02*
X273610D01*
G01X273630Y37090D02*
X273160D01*
G01X273180Y37290D02*
X273640D01*
G01X273660Y37490D02*
X273200D01*
G01X273210Y37680D02*
X273680D01*
G01X273700Y37880D02*
X273230D01*
G01X273240Y38090D02*
X273710D01*
G01X273730Y38290D02*
X273260D01*
G01X273740Y38370D02*
X273830Y38460D01*
G01X274160Y40320D02*
X274280D01*
G01X274000Y40330D02*
X274160Y40320D01*
G01X273910Y40490D02*
X273440D01*
G01X273450Y40590D02*
X273920D01*
G01Y40680D02*
X273460D01*
G01Y40790D02*
X273930D01*
G01X273940Y40880D02*
X273470D01*
G01X273480Y40990D02*
X273950D01*
G01X274350Y42550D02*
X274280D01*
G01X274360Y42540D02*
X274350Y42550D01*
G01X274620Y42470D02*
X274360Y42540D01*
G01X274630Y42460D02*
X274620Y42470D01*
G01X274830Y42290D02*
X274630Y42460D01*
G01X274840Y42280D02*
X274830Y42290D01*
G01X274960Y42050D02*
X274840Y42280D01*
G01X274970Y42030D02*
X274960Y42050D01*
G01X274990Y41750D02*
X274970Y42030D01*
G01X274990Y41740D02*
Y41750D01*
G01X274910Y41480D02*
X274990Y41740D01*
G01X274900Y41470D02*
X274910Y41480D01*
G01X274740Y41270D02*
X274900Y41470D01*
G01X274730Y41250D02*
X274740Y41270D01*
G01X274500Y41130D02*
X274730Y41250D01*
G01X274480Y41130D02*
X274500D01*
G01X274360Y41110D02*
X274480Y41130D01*
G01X274350Y41110D02*
X274360D01*
G01X274290Y41100D02*
X274350Y41110D01*
G01X274270Y41100D02*
X274290D01*
G01X273860Y42380D02*
X274720D01*
G01X274830Y42290D02*
X272940D01*
G01X273220Y42090D02*
X274940D01*
G01X274980Y41880D02*
X273350D01*
G01X275250Y41290D02*
X275880D01*
G01X275980Y41380D02*
X275350D01*
G01X275440Y41490D02*
X276080D01*
G01X276170Y41590D02*
X275540D01*
G01X275640Y41680D02*
X276270D01*
G01X276360Y41790D02*
X275740D01*
G01X275830Y41880D02*
X276460D01*
G01X276560Y41990D02*
X275930D01*
G01X276030Y42090D02*
X276660D01*
G01X276850Y42290D02*
X276220D01*
G01X276410Y42490D02*
X277040D01*
G01X275790Y41180D02*
X275160D01*
G01X275060Y41090D02*
X275690D01*
G01X275590Y40990D02*
X274960D01*
G01X274860Y40880D02*
X275500D01*
G01X275400Y40790D02*
X274770D01*
G01X274670Y40680D02*
X275310D01*
G01X275210Y40590D02*
X274580D01*
G01X274480Y40490D02*
X275110D01*
G01X274960Y38460D02*
X273830D01*
G01X275000Y38480D02*
X274960Y38460D01*
G01X275000Y38490D02*
Y38480D01*
G01Y40310D02*
Y38490D01*
G01Y40320D02*
Y40310D01*
G01X275030Y40400D02*
X275000Y40320D01*
G01X274480Y39740D02*
X274370Y39720D01*
G01X274540Y39640D02*
X274480Y39740D01*
G01X274540Y39040D02*
Y39640D01*
G01X274440Y38940D02*
X274540Y39040D01*
G01X273890Y38940D02*
X274440D01*
G01X274510Y39680D02*
X275000D01*
G01Y39590D02*
X274540D01*
G01Y39490D02*
X275000D01*
G01Y39380D02*
X274540D01*
G01Y39290D02*
X275000D01*
G01Y39180D02*
X274540D01*
G01Y39090D02*
X275000D01*
G01Y38990D02*
X274490D01*
G01X275000Y38790D02*
X272830D01*
G01X272640Y38590D02*
X275000D01*
G01Y39880D02*
X273220D01*
G01Y40090D02*
X275000D01*
G01Y40290D02*
X273220D01*
G01X274280Y40320D02*
X274350Y40350D01*
G01X274380Y40380D02*
X275020D01*
G01X274380Y30090D02*
X272830D01*
G01X273270Y29880D02*
X274570D01*
G01X274350Y40350D02*
X278930Y45090D01*
G01X278960Y44480D02*
X275030Y40400D01*
G01X276120Y42180D02*
X276750D01*
G01X276940Y42380D02*
X276310D01*
G01X276510Y42590D02*
X277140D01*
G01X277240Y42680D02*
X276610D01*
G01X276700Y42790D02*
X277330D01*
G01X277430Y42880D02*
X276800D01*
G01X276900Y42990D02*
X277520D01*
G01X277620Y43090D02*
X276990D01*
G01X277180Y43290D02*
X277810D01*
G01X278010Y43490D02*
X277380D01*
G01X277570Y43680D02*
X278200D01*
G01X278100Y43590D02*
X277480D01*
G01X277670Y43790D02*
X278290D01*
G01X278390Y43880D02*
X277760D01*
G01X277860Y43990D02*
X278490D01*
G01X278590Y44090D02*
X277960D01*
G01X278050Y44180D02*
X278680D01*
G01X278780Y44290D02*
X278150D01*
G01X278250Y44380D02*
X278870D01*
G01X278980Y44590D02*
X278440D01*
G01X278970Y44510D02*
X278980Y44590D01*
G01X278960Y44480D02*
X278970Y44510D01*
G01X278350Y44490D02*
X278960D01*
G01X278980Y45080D02*
X278930Y45090D01*
G01X278980Y44590D02*
Y45080D01*
G01X278920Y45090D02*
X278960D01*
G01X278980Y44990D02*
X278830D01*
G01X278730Y44880D02*
X278980D01*
G01Y44790D02*
X278630D01*
G01X278540Y44680D02*
X278980D01*
G01X277910Y43380D02*
X277280D01*
G01X277090Y43180D02*
X277720D01*
G54D18*
G01X48667Y293000D02*
Y295500D01*
X49667D01*
X50000Y295375D01*
X50250Y295083D01*
X50333Y294750D01*
X50250Y294417D01*
X50042Y294167D01*
X49667Y294042D01*
X48667D01*
G01X51667Y293000D02*
Y295500D01*
X52708D01*
X53042Y295375D01*
X53250Y295208D01*
X53333Y294875D01*
X53250Y294542D01*
X53000Y294333D01*
X52708Y294208D01*
X51667D01*
G01X52708D02*
X53333Y293000D01*
G01X54708Y295083D02*
X54958Y295333D01*
X55250Y295458D01*
X55583Y295500D01*
X56000Y295417D01*
X56292Y295208D01*
X56375Y294958D01*
X56333Y294708D01*
X56167Y294500D01*
X55333Y294083D01*
X54958Y293792D01*
X54708Y293375D01*
X54625Y293000D01*
X56375D01*
G01X57583Y293500D02*
X57833Y293208D01*
X58167Y293042D01*
X58542Y293000D01*
X58875Y293042D01*
X59208Y293250D01*
X59417Y293500D01*
X59458Y293750D01*
X59375Y294042D01*
X59083Y294250D01*
X58792Y294333D01*
X58417D01*
G01X58792D02*
X59042Y294458D01*
X59250Y294667D01*
X59333Y294917D01*
X59250Y295167D01*
X59042Y295375D01*
X58667Y295500D01*
X58292Y295458D01*
X57917Y295292D01*
G01X48667Y299000D02*
Y301500D01*
X49667D01*
X50000Y301375D01*
X50250Y301083D01*
X50333Y300750D01*
X50250Y300417D01*
X50042Y300167D01*
X49667Y300042D01*
X48667D01*
G01X53417Y301292D02*
X53167Y301417D01*
X52875Y301500D01*
X52542D01*
X52167Y301375D01*
X51875Y301167D01*
X51667Y300917D01*
X51500Y300500D01*
X51458Y300125D01*
X51542Y299750D01*
X51667Y299500D01*
X51917Y299250D01*
X52208Y299083D01*
X52500Y299000D01*
X52792D01*
X53083Y299083D01*
X53333Y299208D01*
X53542Y299375D01*
G01X54708Y301083D02*
X54958Y301333D01*
X55250Y301458D01*
X55583Y301500D01*
X56000Y301417D01*
X56292Y301208D01*
X56375Y300958D01*
X56333Y300708D01*
X56167Y300500D01*
X55333Y300083D01*
X54958Y299792D01*
X54708Y299375D01*
X54625Y299000D01*
X56375D01*
G01X58500D02*
Y301500D01*
X58000Y301000D01*
G01Y299000D02*
X59000D01*
G01X42667Y324000D02*
Y326500D01*
X43667D01*
X44000Y326375D01*
X44250Y326083D01*
X44333Y325750D01*
X44250Y325417D01*
X44042Y325167D01*
X43667Y325042D01*
X42667D01*
G01X45667Y324000D02*
Y326500D01*
X46708D01*
X47042Y326375D01*
X47250Y326208D01*
X47333Y325875D01*
X47250Y325542D01*
X47000Y325333D01*
X46708Y325208D01*
X45667D01*
G01X46708D02*
X47333Y324000D01*
G01X48708Y326083D02*
X48958Y326333D01*
X49250Y326458D01*
X49583Y326500D01*
X50000Y326417D01*
X50292Y326208D01*
X50375Y325958D01*
X50333Y325708D01*
X50167Y325500D01*
X49333Y325083D01*
X48958Y324792D01*
X48708Y324375D01*
X48625Y324000D01*
X50375D01*
G01X53000D02*
Y326500D01*
X51458Y324708D01*
X53542D01*
G01X44125Y316000D02*
Y318500D01*
G01X45875D02*
Y316000D01*
G01Y317250D02*
X44125D01*
G01X47208Y318083D02*
X47458Y318333D01*
X47750Y318458D01*
X48083Y318500D01*
X48500Y318417D01*
X48792Y318208D01*
X48875Y317958D01*
X48833Y317708D01*
X48667Y317500D01*
X47833Y317083D01*
X47458Y316792D01*
X47208Y316375D01*
X47125Y316000D01*
X48875D01*
G01X41167Y337000D02*
Y339500D01*
X42167D01*
X42500Y339375D01*
X42750Y339083D01*
X42833Y338750D01*
X42750Y338417D01*
X42542Y338167D01*
X42167Y338042D01*
X41167D01*
G01X44167Y337000D02*
Y339500D01*
X45208D01*
X45542Y339375D01*
X45750Y339208D01*
X45833Y338875D01*
X45750Y338542D01*
X45500Y338333D01*
X45208Y338208D01*
X44167D01*
G01X45208D02*
X45833Y337000D01*
G01X48000D02*
Y339500D01*
X47500Y339000D01*
G01Y337000D02*
X48500D01*
G01X51000D02*
X51292Y337042D01*
X51625Y337167D01*
X51833Y337375D01*
X51917Y337667D01*
X51833Y337958D01*
X51583Y338208D01*
X51208Y338333D01*
X50792D01*
X50542Y338417D01*
X50333Y338625D01*
X50250Y338917D01*
X50375Y339208D01*
X50667Y339417D01*
X51000Y339500D01*
X51333Y339417D01*
X51625Y339208D01*
X51750Y338917D01*
X51667Y338625D01*
X51458Y338417D01*
X51208Y338333D01*
X50792D01*
X50417Y338208D01*
X50167Y337958D01*
X50083Y337667D01*
X50167Y337375D01*
X50375Y337167D01*
X50708Y337042D01*
X51000Y337000D01*
G01X41167Y329000D02*
Y331500D01*
X42167D01*
X42500Y331375D01*
X42750Y331083D01*
X42833Y330750D01*
X42750Y330417D01*
X42542Y330167D01*
X42167Y330042D01*
X41167D01*
G01X45917Y331292D02*
X45667Y331417D01*
X45375Y331500D01*
X45042D01*
X44667Y331375D01*
X44375Y331167D01*
X44167Y330917D01*
X44000Y330500D01*
X43958Y330125D01*
X44042Y329750D01*
X44167Y329500D01*
X44417Y329250D01*
X44708Y329083D01*
X45000Y329000D01*
X45292D01*
X45583Y329083D01*
X45833Y329208D01*
X46042Y329375D01*
G01X47208Y331083D02*
X47458Y331333D01*
X47750Y331458D01*
X48083Y331500D01*
X48500Y331417D01*
X48792Y331208D01*
X48875Y330958D01*
X48833Y330708D01*
X48667Y330500D01*
X47833Y330083D01*
X47458Y329792D01*
X47208Y329375D01*
X47125Y329000D01*
X48875D01*
G01X51000Y331500D02*
X50667Y331417D01*
X50417Y331208D01*
X50250Y330958D01*
X50125Y330625D01*
X50083Y330250D01*
X50125Y329875D01*
X50250Y329542D01*
X50417Y329292D01*
X50667Y329083D01*
X51000Y329000D01*
X51333Y329083D01*
X51583Y329292D01*
X51750Y329542D01*
X51875Y329875D01*
X51917Y330250D01*
X51875Y330625D01*
X51750Y330958D01*
X51583Y331208D01*
X51333Y331417D01*
X51000Y331500D01*
G01X41167Y333000D02*
Y335500D01*
X42167D01*
X42500Y335375D01*
X42750Y335083D01*
X42833Y334750D01*
X42750Y334417D01*
X42542Y334167D01*
X42167Y334042D01*
X41167D01*
G01X45917Y335292D02*
X45667Y335417D01*
X45375Y335500D01*
X45042D01*
X44667Y335375D01*
X44375Y335167D01*
X44167Y334917D01*
X44000Y334500D01*
X43958Y334125D01*
X44042Y333750D01*
X44167Y333500D01*
X44417Y333250D01*
X44708Y333083D01*
X45000Y333000D01*
X45292D01*
X45583Y333083D01*
X45833Y333208D01*
X46042Y333375D01*
G01X47208Y335083D02*
X47458Y335333D01*
X47750Y335458D01*
X48083Y335500D01*
X48500Y335417D01*
X48792Y335208D01*
X48875Y334958D01*
X48833Y334708D01*
X48667Y334500D01*
X47833Y334083D01*
X47458Y333792D01*
X47208Y333375D01*
X47125Y333000D01*
X48875D01*
G01X50208Y334042D02*
X50500Y334333D01*
X50750Y334500D01*
X51083Y334583D01*
X51375Y334500D01*
X51583Y334333D01*
X51750Y334083D01*
X51792Y333792D01*
X51750Y333542D01*
X51583Y333292D01*
X51333Y333083D01*
X51042Y333000D01*
X50708Y333083D01*
X50417Y333333D01*
X50250Y333708D01*
X50208Y334125D01*
X50292Y334667D01*
X50417Y334958D01*
X50625Y335250D01*
X50917Y335458D01*
X51208Y335500D01*
X51500Y335417D01*
X51708Y335208D01*
G01X60667Y280189D02*
Y282689D01*
X61667D01*
X62000Y282564D01*
X62250Y282272D01*
X62333Y281939D01*
X62250Y281606D01*
X62042Y281356D01*
X61667Y281231D01*
X60667D01*
G01X63667Y280189D02*
Y282689D01*
X64708D01*
X65042Y282564D01*
X65250Y282397D01*
X65333Y282064D01*
X65250Y281731D01*
X65000Y281522D01*
X64708Y281397D01*
X63667D01*
G01X64708D02*
X65333Y280189D01*
G01X66708Y282272D02*
X66958Y282522D01*
X67250Y282647D01*
X67583Y282689D01*
X68000Y282606D01*
X68292Y282397D01*
X68375Y282147D01*
X68333Y281897D01*
X68167Y281689D01*
X67333Y281272D01*
X66958Y280981D01*
X66708Y280564D01*
X66625Y280189D01*
X68375D01*
G01X69708Y282272D02*
X69958Y282522D01*
X70250Y282647D01*
X70583Y282689D01*
X71000Y282606D01*
X71292Y282397D01*
X71375Y282147D01*
X71333Y281897D01*
X71167Y281689D01*
X70333Y281272D01*
X69958Y280981D01*
X69708Y280564D01*
X69625Y280189D01*
X71375D01*
G01X60667Y284689D02*
Y287189D01*
X61667D01*
X62000Y287064D01*
X62250Y286772D01*
X62333Y286439D01*
X62250Y286106D01*
X62042Y285856D01*
X61667Y285731D01*
X60667D01*
G01X65417Y286981D02*
X65167Y287106D01*
X64875Y287189D01*
X64542D01*
X64167Y287064D01*
X63875Y286856D01*
X63667Y286606D01*
X63500Y286189D01*
X63458Y285814D01*
X63542Y285439D01*
X63667Y285189D01*
X63917Y284939D01*
X64208Y284772D01*
X64500Y284689D01*
X64792D01*
X65083Y284772D01*
X65333Y284897D01*
X65542Y285064D01*
G01X66708Y286772D02*
X66958Y287022D01*
X67250Y287147D01*
X67583Y287189D01*
X68000Y287106D01*
X68292Y286897D01*
X68375Y286647D01*
X68333Y286397D01*
X68167Y286189D01*
X67333Y285772D01*
X66958Y285481D01*
X66708Y285064D01*
X66625Y284689D01*
X68375D01*
G01X69708Y286772D02*
X69958Y287022D01*
X70250Y287147D01*
X70583Y287189D01*
X71000Y287106D01*
X71292Y286897D01*
X71375Y286647D01*
X71333Y286397D01*
X71167Y286189D01*
X70333Y285772D01*
X69958Y285481D01*
X69708Y285064D01*
X69625Y284689D01*
X71375D01*
G01X69167Y348311D02*
Y350811D01*
X70167D01*
X70500Y350686D01*
X70750Y350394D01*
X70833Y350061D01*
X70750Y349728D01*
X70542Y349478D01*
X70167Y349353D01*
X69167D01*
G01X72167Y348311D02*
Y350811D01*
X73208D01*
X73542Y350686D01*
X73750Y350519D01*
X73833Y350186D01*
X73750Y349853D01*
X73500Y349644D01*
X73208Y349519D01*
X72167D01*
G01X73208D02*
X73833Y348311D01*
G01X75208Y350394D02*
X75458Y350644D01*
X75750Y350769D01*
X76083Y350811D01*
X76500Y350728D01*
X76792Y350519D01*
X76875Y350269D01*
X76833Y350019D01*
X76667Y349811D01*
X75833Y349394D01*
X75458Y349103D01*
X75208Y348686D01*
X75125Y348311D01*
X76875D01*
G01X79000Y350811D02*
X78667Y350728D01*
X78417Y350519D01*
X78250Y350269D01*
X78125Y349936D01*
X78083Y349561D01*
X78125Y349186D01*
X78250Y348853D01*
X78417Y348603D01*
X78667Y348394D01*
X79000Y348311D01*
X79333Y348394D01*
X79583Y348603D01*
X79750Y348853D01*
X79875Y349186D01*
X79917Y349561D01*
X79875Y349936D01*
X79750Y350269D01*
X79583Y350519D01*
X79333Y350728D01*
X79000Y350811D01*
G01X64000Y345000D02*
X66500D01*
G01X64000Y344042D02*
Y345958D01*
G01X66500Y347167D02*
X64000D01*
Y348167D01*
X64125Y348500D01*
X64417Y348750D01*
X64750Y348833D01*
X65083Y348750D01*
X65333Y348542D01*
X65458Y348167D01*
Y347167D01*
G01X66125Y350083D02*
X66333Y350333D01*
X66458Y350625D01*
X66500Y351000D01*
X66417Y351375D01*
X66250Y351667D01*
X65958Y351875D01*
X65625Y351917D01*
X65292Y351833D01*
X65083Y351625D01*
X64917Y351333D01*
X64875Y351042D01*
X64917Y350750D01*
X65083Y350375D01*
X64000Y350500D01*
Y351625D01*
G01X75167Y270000D02*
Y272500D01*
X76167D01*
X76500Y272375D01*
X76750Y272083D01*
X76833Y271750D01*
X76750Y271417D01*
X76542Y271167D01*
X76167Y271042D01*
X75167D01*
G01X79917Y272292D02*
X79667Y272417D01*
X79375Y272500D01*
X79042D01*
X78667Y272375D01*
X78375Y272167D01*
X78167Y271917D01*
X78000Y271500D01*
X77958Y271125D01*
X78042Y270750D01*
X78167Y270500D01*
X78417Y270250D01*
X78708Y270083D01*
X79000Y270000D01*
X79292D01*
X79583Y270083D01*
X79833Y270208D01*
X80042Y270375D01*
G01X81208Y272083D02*
X81458Y272333D01*
X81750Y272458D01*
X82083Y272500D01*
X82500Y272417D01*
X82792Y272208D01*
X82875Y271958D01*
X82833Y271708D01*
X82667Y271500D01*
X81833Y271083D01*
X81458Y270792D01*
X81208Y270375D01*
X81125Y270000D01*
X82875D01*
G01X84083Y270500D02*
X84333Y270208D01*
X84667Y270042D01*
X85042Y270000D01*
X85375Y270042D01*
X85708Y270250D01*
X85917Y270500D01*
X85958Y270750D01*
X85875Y271042D01*
X85583Y271250D01*
X85292Y271333D01*
X84917D01*
G01X85292D02*
X85542Y271458D01*
X85750Y271667D01*
X85833Y271917D01*
X85750Y272167D01*
X85542Y272375D01*
X85167Y272500D01*
X84792Y272458D01*
X84417Y272292D01*
G01X75167Y274000D02*
Y276500D01*
X76167D01*
X76500Y276375D01*
X76750Y276083D01*
X76833Y275750D01*
X76750Y275417D01*
X76542Y275167D01*
X76167Y275042D01*
X75167D01*
G01X79917Y276292D02*
X79667Y276417D01*
X79375Y276500D01*
X79042D01*
X78667Y276375D01*
X78375Y276167D01*
X78167Y275917D01*
X78000Y275500D01*
X77958Y275125D01*
X78042Y274750D01*
X78167Y274500D01*
X78417Y274250D01*
X78708Y274083D01*
X79000Y274000D01*
X79292D01*
X79583Y274083D01*
X79833Y274208D01*
X80042Y274375D01*
G01X81208Y276083D02*
X81458Y276333D01*
X81750Y276458D01*
X82083Y276500D01*
X82500Y276417D01*
X82792Y276208D01*
X82875Y275958D01*
X82833Y275708D01*
X82667Y275500D01*
X81833Y275083D01*
X81458Y274792D01*
X81208Y274375D01*
X81125Y274000D01*
X82875D01*
G01X85500D02*
Y276500D01*
X83958Y274708D01*
X86042D01*
G01X75167Y278000D02*
Y280500D01*
X76167D01*
X76500Y280375D01*
X76750Y280083D01*
X76833Y279750D01*
X76750Y279417D01*
X76542Y279167D01*
X76167Y279042D01*
X75167D01*
G01X79917Y280292D02*
X79667Y280417D01*
X79375Y280500D01*
X79042D01*
X78667Y280375D01*
X78375Y280167D01*
X78167Y279917D01*
X78000Y279500D01*
X77958Y279125D01*
X78042Y278750D01*
X78167Y278500D01*
X78417Y278250D01*
X78708Y278083D01*
X79000Y278000D01*
X79292D01*
X79583Y278083D01*
X79833Y278208D01*
X80042Y278375D01*
G01X81208Y280083D02*
X81458Y280333D01*
X81750Y280458D01*
X82083Y280500D01*
X82500Y280417D01*
X82792Y280208D01*
X82875Y279958D01*
X82833Y279708D01*
X82667Y279500D01*
X81833Y279083D01*
X81458Y278792D01*
X81208Y278375D01*
X81125Y278000D01*
X82875D01*
G01X84083Y278375D02*
X84333Y278167D01*
X84625Y278042D01*
X85000Y278000D01*
X85375Y278083D01*
X85667Y278250D01*
X85875Y278542D01*
X85917Y278875D01*
X85833Y279208D01*
X85625Y279417D01*
X85333Y279583D01*
X85042Y279625D01*
X84750Y279583D01*
X84375Y279417D01*
X84500Y280500D01*
X85625D01*
G01X84000Y310667D02*
X81500D01*
Y311667D01*
X81625Y312000D01*
X81917Y312250D01*
X82250Y312333D01*
X82583Y312250D01*
X82833Y312042D01*
X82958Y311667D01*
Y310667D01*
G01X81500Y313583D02*
X83292D01*
X83667Y313750D01*
X83917Y314083D01*
X84000Y314500D01*
X83917Y314917D01*
X83667Y315250D01*
X83292Y315417D01*
X81500D01*
G01X81917Y316708D02*
X81667Y316958D01*
X81542Y317250D01*
X81500Y317583D01*
X81583Y318000D01*
X81792Y318292D01*
X82042Y318375D01*
X82292Y318333D01*
X82500Y318167D01*
X82917Y317333D01*
X83208Y316958D01*
X83625Y316708D01*
X84000Y316625D01*
Y318375D01*
G01X85743Y315752D02*
Y318252D01*
X86784D01*
X87118Y318127D01*
X87326Y317960D01*
X87409Y317627D01*
X87326Y317294D01*
X87076Y317085D01*
X86784Y316960D01*
X85743D01*
G01X86784D02*
X87409Y315752D01*
G01X88659Y316252D02*
X88909Y315960D01*
X89243Y315794D01*
X89618Y315752D01*
X89951Y315794D01*
X90284Y316002D01*
X90493Y316252D01*
X90534Y316502D01*
X90451Y316794D01*
X90159Y317002D01*
X89868Y317085D01*
X89493D01*
G01X89868D02*
X90118Y317210D01*
X90326Y317419D01*
X90409Y317669D01*
X90326Y317919D01*
X90118Y318127D01*
X89743Y318252D01*
X89368Y318210D01*
X88993Y318044D01*
G01X92576Y315752D02*
Y318252D01*
X92076Y317752D01*
G01Y315752D02*
X93076D01*
G01X85667Y323500D02*
Y326000D01*
X86708D01*
X87042Y325875D01*
X87250Y325708D01*
X87333Y325375D01*
X87250Y325042D01*
X87000Y324833D01*
X86708Y324708D01*
X85667D01*
G01X86708D02*
X87333Y323500D01*
G01X88583Y324000D02*
X88833Y323708D01*
X89167Y323542D01*
X89542Y323500D01*
X89875Y323542D01*
X90208Y323750D01*
X90417Y324000D01*
X90458Y324250D01*
X90375Y324542D01*
X90083Y324750D01*
X89792Y324833D01*
X89417D01*
G01X89792D02*
X90042Y324958D01*
X90250Y325167D01*
X90333Y325417D01*
X90250Y325667D01*
X90042Y325875D01*
X89667Y326000D01*
X89292Y325958D01*
X88917Y325792D01*
G01X91708Y325583D02*
X91958Y325833D01*
X92250Y325958D01*
X92583Y326000D01*
X93000Y325917D01*
X93292Y325708D01*
X93375Y325458D01*
X93333Y325208D01*
X93167Y325000D01*
X92333Y324583D01*
X91958Y324292D01*
X91708Y323875D01*
X91625Y323500D01*
X93375D01*
G01X85743Y319752D02*
Y322252D01*
X86784D01*
X87118Y322127D01*
X87326Y321960D01*
X87409Y321627D01*
X87326Y321294D01*
X87076Y321085D01*
X86784Y320960D01*
X85743D01*
G01X86784D02*
X87409Y319752D01*
G01X88784Y321835D02*
X89034Y322085D01*
X89326Y322210D01*
X89659Y322252D01*
X90076Y322169D01*
X90368Y321960D01*
X90451Y321710D01*
X90409Y321460D01*
X90243Y321252D01*
X89409Y320835D01*
X89034Y320544D01*
X88784Y320127D01*
X88701Y319752D01*
X90451D01*
G01X92576D02*
X92868Y319794D01*
X93201Y319919D01*
X93409Y320127D01*
X93493Y320419D01*
X93409Y320710D01*
X93159Y320960D01*
X92784Y321085D01*
X92368D01*
X92118Y321169D01*
X91909Y321377D01*
X91826Y321669D01*
X91951Y321960D01*
X92243Y322169D01*
X92576Y322252D01*
X92909Y322169D01*
X93201Y321960D01*
X93326Y321669D01*
X93243Y321377D01*
X93034Y321169D01*
X92784Y321085D01*
X92368D01*
X91993Y320960D01*
X91743Y320710D01*
X91659Y320419D01*
X91743Y320127D01*
X91951Y319919D01*
X92284Y319794D01*
X92576Y319752D01*
G01X87500Y336167D02*
X85000D01*
Y337167D01*
X85125Y337500D01*
X85417Y337750D01*
X85750Y337833D01*
X86083Y337750D01*
X86333Y337542D01*
X86458Y337167D01*
Y336167D01*
G01X85208Y340917D02*
X85083Y340667D01*
X85000Y340375D01*
Y340042D01*
X85125Y339667D01*
X85333Y339375D01*
X85583Y339167D01*
X86000Y339000D01*
X86375Y338958D01*
X86750Y339042D01*
X87000Y339167D01*
X87250Y339417D01*
X87417Y339708D01*
X87500Y340000D01*
Y340292D01*
X87417Y340583D01*
X87292Y340833D01*
X87125Y341042D01*
G01X85417Y342208D02*
X85167Y342458D01*
X85042Y342750D01*
X85000Y343083D01*
X85083Y343500D01*
X85292Y343792D01*
X85542Y343875D01*
X85792Y343833D01*
X86000Y343667D01*
X86417Y342833D01*
X86708Y342458D01*
X87125Y342208D01*
X87500Y342125D01*
Y343875D01*
G01Y345917D02*
X86958Y346000D01*
X86500Y346125D01*
X86083Y346292D01*
X85625Y346500D01*
X85000Y346833D01*
Y345167D01*
G01X83500Y336167D02*
X81000D01*
Y337167D01*
X81125Y337500D01*
X81417Y337750D01*
X81750Y337833D01*
X82083Y337750D01*
X82333Y337542D01*
X82458Y337167D01*
Y336167D01*
G01X81208Y340917D02*
X81083Y340667D01*
X81000Y340375D01*
Y340042D01*
X81125Y339667D01*
X81333Y339375D01*
X81583Y339167D01*
X82000Y339000D01*
X82375Y338958D01*
X82750Y339042D01*
X83000Y339167D01*
X83250Y339417D01*
X83417Y339708D01*
X83500Y340000D01*
Y340292D01*
X83417Y340583D01*
X83292Y340833D01*
X83125Y341042D01*
G01X81417Y342208D02*
X81167Y342458D01*
X81042Y342750D01*
X81000Y343083D01*
X81083Y343500D01*
X81292Y343792D01*
X81542Y343875D01*
X81792Y343833D01*
X82000Y343667D01*
X82417Y342833D01*
X82708Y342458D01*
X83125Y342208D01*
X83500Y342125D01*
Y343875D01*
G01Y346000D02*
X83458Y346292D01*
X83333Y346625D01*
X83125Y346833D01*
X82833Y346917D01*
X82542Y346833D01*
X82292Y346583D01*
X82167Y346208D01*
Y345792D01*
X82083Y345542D01*
X81875Y345333D01*
X81583Y345250D01*
X81292Y345375D01*
X81083Y345667D01*
X81000Y346000D01*
X81083Y346333D01*
X81292Y346625D01*
X81583Y346750D01*
X81875Y346667D01*
X82083Y346458D01*
X82167Y346208D01*
Y345792D01*
X82292Y345417D01*
X82542Y345167D01*
X82833Y345083D01*
X83125Y345167D01*
X83333Y345375D01*
X83458Y345708D01*
X83500Y346000D01*
G01X96000Y268667D02*
X93500D01*
Y269708D01*
X93625Y270042D01*
X93792Y270250D01*
X94125Y270333D01*
X94458Y270250D01*
X94667Y270000D01*
X94792Y269708D01*
Y268667D01*
G01Y269708D02*
X96000Y270333D01*
G01X95625Y271583D02*
X95833Y271833D01*
X95958Y272125D01*
X96000Y272500D01*
X95917Y272875D01*
X95750Y273167D01*
X95458Y273375D01*
X95125Y273417D01*
X94792Y273333D01*
X94583Y273125D01*
X94417Y272833D01*
X94375Y272542D01*
X94417Y272250D01*
X94583Y271875D01*
X93500Y272000D01*
Y273125D01*
G01X94958Y274708D02*
X94667Y275000D01*
X94500Y275250D01*
X94417Y275583D01*
X94500Y275875D01*
X94667Y276083D01*
X94917Y276250D01*
X95208Y276292D01*
X95458Y276250D01*
X95708Y276083D01*
X95917Y275833D01*
X96000Y275542D01*
X95917Y275208D01*
X95667Y274917D01*
X95292Y274750D01*
X94875Y274708D01*
X94333Y274792D01*
X94042Y274917D01*
X93750Y275125D01*
X93542Y275417D01*
X93500Y275708D01*
X93583Y276000D01*
X93792Y276208D01*
G01X100500Y268667D02*
X98000D01*
Y269708D01*
X98125Y270042D01*
X98292Y270250D01*
X98625Y270333D01*
X98958Y270250D01*
X99167Y270000D01*
X99292Y269708D01*
Y268667D01*
G01Y269708D02*
X100500Y270333D01*
G01X100125Y271583D02*
X100333Y271833D01*
X100458Y272125D01*
X100500Y272500D01*
X100417Y272875D01*
X100250Y273167D01*
X99958Y273375D01*
X99625Y273417D01*
X99292Y273333D01*
X99083Y273125D01*
X98917Y272833D01*
X98875Y272542D01*
X98917Y272250D01*
X99083Y271875D01*
X98000Y272000D01*
Y273125D01*
G01X100125Y274583D02*
X100333Y274833D01*
X100458Y275125D01*
X100500Y275500D01*
X100417Y275875D01*
X100250Y276167D01*
X99958Y276375D01*
X99625Y276417D01*
X99292Y276333D01*
X99083Y276125D01*
X98917Y275833D01*
X98875Y275542D01*
X98917Y275250D01*
X99083Y274875D01*
X98000Y275000D01*
Y276125D01*
G01X102208Y270417D02*
X102083Y270167D01*
X102000Y269875D01*
Y269542D01*
X102125Y269167D01*
X102333Y268875D01*
X102583Y268667D01*
X103000Y268500D01*
X103375Y268458D01*
X103750Y268542D01*
X104000Y268667D01*
X104250Y268917D01*
X104417Y269208D01*
X104500Y269500D01*
Y269792D01*
X104417Y270083D01*
X104292Y270333D01*
X104125Y270542D01*
G01X104500Y272500D02*
X102000D01*
X102500Y272000D01*
G01X104500D02*
Y273000D01*
G01X102000Y275500D02*
X102083Y275167D01*
X102292Y274917D01*
X102542Y274750D01*
X102875Y274625D01*
X103250Y274583D01*
X103625Y274625D01*
X103958Y274750D01*
X104208Y274917D01*
X104417Y275167D01*
X104500Y275500D01*
X104417Y275833D01*
X104208Y276083D01*
X103958Y276250D01*
X103625Y276375D01*
X103250Y276417D01*
X102875Y276375D01*
X102542Y276250D01*
X102292Y276083D01*
X102083Y275833D01*
X102000Y275500D01*
G01X91917Y311292D02*
X91667Y311417D01*
X91375Y311500D01*
X91042D01*
X90667Y311375D01*
X90375Y311167D01*
X90167Y310917D01*
X90000Y310500D01*
X89958Y310125D01*
X90042Y309750D01*
X90167Y309500D01*
X90417Y309250D01*
X90708Y309083D01*
X91000Y309000D01*
X91292D01*
X91583Y309083D01*
X91833Y309208D01*
X92042Y309375D01*
G01X94000Y309000D02*
X94292Y309042D01*
X94625Y309167D01*
X94833Y309375D01*
X94917Y309667D01*
X94833Y309958D01*
X94583Y310208D01*
X94208Y310333D01*
X93792D01*
X93542Y310417D01*
X93333Y310625D01*
X93250Y310917D01*
X93375Y311208D01*
X93667Y311417D01*
X94000Y311500D01*
X94333Y311417D01*
X94625Y311208D01*
X94750Y310917D01*
X94667Y310625D01*
X94458Y310417D01*
X94208Y310333D01*
X93792D01*
X93417Y310208D01*
X93167Y309958D01*
X93083Y309667D01*
X93167Y309375D01*
X93375Y309167D01*
X93708Y309042D01*
X94000Y309000D01*
G01X90083Y299500D02*
Y297708D01*
X90250Y297333D01*
X90583Y297083D01*
X91000Y297000D01*
X91417Y297083D01*
X91750Y297333D01*
X91917Y297708D01*
Y299500D01*
G01X93917Y297000D02*
X94000Y297542D01*
X94125Y298000D01*
X94292Y298417D01*
X94500Y298875D01*
X94833Y299500D01*
X93167D01*
G01X99208Y347417D02*
X99083Y347167D01*
X99000Y346875D01*
Y346542D01*
X99125Y346167D01*
X99333Y345875D01*
X99583Y345667D01*
X100000Y345500D01*
X100375Y345458D01*
X100750Y345542D01*
X101000Y345667D01*
X101250Y345917D01*
X101417Y346208D01*
X101500Y346500D01*
Y346792D01*
X101417Y347083D01*
X101292Y347333D01*
X101125Y347542D01*
G01X101500Y349417D02*
X100958Y349500D01*
X100500Y349625D01*
X100083Y349792D01*
X99625Y350000D01*
X99000Y350333D01*
Y348667D01*
G01X103583Y351000D02*
Y349208D01*
X103750Y348833D01*
X104083Y348583D01*
X104500Y348500D01*
X104917Y348583D01*
X105250Y348833D01*
X105417Y349208D01*
Y351000D01*
G01X108000Y348500D02*
Y351000D01*
X106458Y349208D01*
X108542D01*
G01X115500Y270167D02*
X113000D01*
Y271208D01*
X113125Y271542D01*
X113292Y271750D01*
X113625Y271833D01*
X113958Y271750D01*
X114167Y271500D01*
X114292Y271208D01*
Y270167D01*
G01Y271208D02*
X115500Y271833D01*
G01X115125Y273083D02*
X115333Y273333D01*
X115458Y273625D01*
X115500Y274000D01*
X115417Y274375D01*
X115250Y274667D01*
X114958Y274875D01*
X114625Y274917D01*
X114292Y274833D01*
X114083Y274625D01*
X113917Y274333D01*
X113875Y274042D01*
X113917Y273750D01*
X114083Y273375D01*
X113000Y273500D01*
Y274625D01*
G01X115000Y276083D02*
X115292Y276333D01*
X115458Y276667D01*
X115500Y277042D01*
X115458Y277375D01*
X115250Y277708D01*
X115000Y277917D01*
X114750Y277958D01*
X114458Y277875D01*
X114250Y277583D01*
X114167Y277292D01*
Y276917D01*
G01Y277292D02*
X114042Y277542D01*
X113833Y277750D01*
X113583Y277833D01*
X113333Y277750D01*
X113125Y277542D01*
X113000Y277167D01*
X113042Y276792D01*
X113208Y276417D01*
G01X120500Y268667D02*
X118000D01*
Y269708D01*
X118125Y270042D01*
X118292Y270250D01*
X118625Y270333D01*
X118958Y270250D01*
X119167Y270000D01*
X119292Y269708D01*
Y268667D01*
G01Y269708D02*
X120500Y270333D01*
G01X120125Y271583D02*
X120333Y271833D01*
X120458Y272125D01*
X120500Y272500D01*
X120417Y272875D01*
X120250Y273167D01*
X119958Y273375D01*
X119625Y273417D01*
X119292Y273333D01*
X119083Y273125D01*
X118917Y272833D01*
X118875Y272542D01*
X118917Y272250D01*
X119083Y271875D01*
X118000Y272000D01*
Y273125D01*
G01X118417Y274708D02*
X118167Y274958D01*
X118042Y275250D01*
X118000Y275583D01*
X118083Y276000D01*
X118292Y276292D01*
X118542Y276375D01*
X118792Y276333D01*
X119000Y276167D01*
X119417Y275333D01*
X119708Y274958D01*
X120125Y274708D01*
X120500Y274625D01*
Y276375D01*
G01X108708Y271917D02*
X108583Y271667D01*
X108500Y271375D01*
Y271042D01*
X108625Y270667D01*
X108833Y270375D01*
X109083Y270167D01*
X109500Y270000D01*
X109875Y269958D01*
X110250Y270042D01*
X110500Y270167D01*
X110750Y270417D01*
X110917Y270708D01*
X111000Y271000D01*
Y271292D01*
X110917Y271583D01*
X110792Y271833D01*
X110625Y272042D01*
G01X110708Y273292D02*
X110917Y273583D01*
X111000Y273917D01*
X110917Y274250D01*
X110667Y274542D01*
X110292Y274750D01*
X109917Y274833D01*
X109458D01*
X109083Y274750D01*
X108750Y274542D01*
X108583Y274292D01*
X108500Y274000D01*
X108583Y273667D01*
X108750Y273417D01*
X109000Y273250D01*
X109333Y273167D01*
X109625Y273250D01*
X109917Y273458D01*
X110083Y273708D01*
X110125Y274000D01*
X110042Y274333D01*
X109833Y274583D01*
X109458Y274833D01*
G01X122083Y282500D02*
Y280708D01*
X122250Y280333D01*
X122583Y280083D01*
X123000Y280000D01*
X123417Y280083D01*
X123750Y280333D01*
X123917Y280708D01*
Y282500D01*
G01X125208Y281042D02*
X125500Y281333D01*
X125750Y281500D01*
X126083Y281583D01*
X126375Y281500D01*
X126583Y281333D01*
X126750Y281083D01*
X126792Y280792D01*
X126750Y280542D01*
X126583Y280292D01*
X126333Y280083D01*
X126042Y280000D01*
X125708Y280083D01*
X125417Y280333D01*
X125250Y280708D01*
X125208Y281125D01*
X125292Y281667D01*
X125417Y281958D01*
X125625Y282250D01*
X125917Y282458D01*
X126208Y282500D01*
X126500Y282417D01*
X126708Y282208D01*
G01X118752Y348591D02*
X116252D01*
Y349632D01*
X116377Y349966D01*
X116544Y350174D01*
X116877Y350257D01*
X117210Y350174D01*
X117419Y349924D01*
X117544Y349632D01*
Y348591D01*
G01Y349632D02*
X118752Y350257D01*
G01X118252Y351507D02*
X118544Y351757D01*
X118710Y352091D01*
X118752Y352466D01*
X118710Y352799D01*
X118502Y353132D01*
X118252Y353341D01*
X118002Y353382D01*
X117710Y353299D01*
X117502Y353007D01*
X117419Y352716D01*
Y352341D01*
G01Y352716D02*
X117294Y352966D01*
X117085Y353174D01*
X116835Y353257D01*
X116585Y353174D01*
X116377Y352966D01*
X116252Y352591D01*
X116294Y352216D01*
X116460Y351841D01*
G01X118460Y354716D02*
X118669Y355007D01*
X118752Y355341D01*
X118669Y355674D01*
X118419Y355966D01*
X118044Y356174D01*
X117669Y356257D01*
X117210D01*
X116835Y356174D01*
X116502Y355966D01*
X116335Y355716D01*
X116252Y355424D01*
X116335Y355091D01*
X116502Y354841D01*
X116752Y354674D01*
X117085Y354591D01*
X117377Y354674D01*
X117669Y354882D01*
X117835Y355132D01*
X117877Y355424D01*
X117794Y355757D01*
X117585Y356007D01*
X117210Y356257D01*
G01X114752Y348591D02*
X112252D01*
Y349632D01*
X112377Y349966D01*
X112544Y350174D01*
X112877Y350257D01*
X113210Y350174D01*
X113419Y349924D01*
X113544Y349632D01*
Y348591D01*
G01Y349632D02*
X114752Y350257D01*
G01X114252Y351507D02*
X114544Y351757D01*
X114710Y352091D01*
X114752Y352466D01*
X114710Y352799D01*
X114502Y353132D01*
X114252Y353341D01*
X114002Y353382D01*
X113710Y353299D01*
X113502Y353007D01*
X113419Y352716D01*
Y352341D01*
G01Y352716D02*
X113294Y352966D01*
X113085Y353174D01*
X112835Y353257D01*
X112585Y353174D01*
X112377Y352966D01*
X112252Y352591D01*
X112294Y352216D01*
X112460Y351841D01*
G01X114752Y355424D02*
X114710Y355716D01*
X114585Y356049D01*
X114377Y356257D01*
X114085Y356341D01*
X113794Y356257D01*
X113544Y356007D01*
X113419Y355632D01*
Y355216D01*
X113335Y354966D01*
X113127Y354757D01*
X112835Y354674D01*
X112544Y354799D01*
X112335Y355091D01*
X112252Y355424D01*
X112335Y355757D01*
X112544Y356049D01*
X112835Y356174D01*
X113127Y356091D01*
X113335Y355882D01*
X113419Y355632D01*
Y355216D01*
X113544Y354841D01*
X113794Y354591D01*
X114085Y354507D01*
X114377Y354591D01*
X114585Y354799D01*
X114710Y355132D01*
X114752Y355424D01*
G01X123000Y348478D02*
X120500D01*
Y349519D01*
X120625Y349853D01*
X120792Y350061D01*
X121125Y350144D01*
X121458Y350061D01*
X121667Y349811D01*
X121792Y349519D01*
Y348478D01*
G01Y349519D02*
X123000Y350144D01*
G01Y352811D02*
X120500D01*
X122292Y351269D01*
Y353353D01*
G01X123000Y355311D02*
X120500D01*
X121000Y354811D01*
G01X123000D02*
Y355811D01*
G01X128708Y281917D02*
X128583Y281667D01*
X128500Y281375D01*
Y281042D01*
X128625Y280667D01*
X128833Y280375D01*
X129083Y280167D01*
X129500Y280000D01*
X129875Y279958D01*
X130250Y280042D01*
X130500Y280167D01*
X130750Y280417D01*
X130917Y280708D01*
X131000Y281000D01*
Y281292D01*
X130917Y281583D01*
X130792Y281833D01*
X130625Y282042D01*
G01X131000Y284000D02*
X128500D01*
X129000Y283500D01*
G01X131000D02*
Y284500D01*
G01Y287000D02*
X128500D01*
X129000Y286500D01*
G01X131000D02*
Y287500D01*
G01X140500Y297667D02*
X138000D01*
Y298667D01*
X138125Y299000D01*
X138417Y299250D01*
X138750Y299333D01*
X139083Y299250D01*
X139333Y299042D01*
X139458Y298667D01*
Y297667D01*
G01X138000Y300667D02*
X140500D01*
Y302333D01*
G01X138417Y303708D02*
X138167Y303958D01*
X138042Y304250D01*
X138000Y304583D01*
X138083Y305000D01*
X138292Y305292D01*
X138542Y305375D01*
X138792Y305333D01*
X139000Y305167D01*
X139417Y304333D01*
X139708Y303958D01*
X140125Y303708D01*
X140500Y303625D01*
Y305375D01*
G01Y340667D02*
X138000D01*
Y341667D01*
X138125Y342000D01*
X138417Y342250D01*
X138750Y342333D01*
X139083Y342250D01*
X139333Y342042D01*
X139458Y341667D01*
Y340667D01*
G01X138208Y345417D02*
X138083Y345167D01*
X138000Y344875D01*
Y344542D01*
X138125Y344167D01*
X138333Y343875D01*
X138583Y343667D01*
X139000Y343500D01*
X139375Y343458D01*
X139750Y343542D01*
X140000Y343667D01*
X140250Y343917D01*
X140417Y344208D01*
X140500Y344500D01*
Y344792D01*
X140417Y345083D01*
X140292Y345333D01*
X140125Y345542D01*
G01X140000Y346583D02*
X140292Y346833D01*
X140458Y347167D01*
X140500Y347542D01*
X140458Y347875D01*
X140250Y348208D01*
X140000Y348417D01*
X139750Y348458D01*
X139458Y348375D01*
X139250Y348083D01*
X139167Y347792D01*
Y347417D01*
G01Y347792D02*
X139042Y348042D01*
X138833Y348250D01*
X138583Y348333D01*
X138333Y348250D01*
X138125Y348042D01*
X138000Y347667D01*
X138042Y347292D01*
X138208Y346917D01*
G01X140125Y349583D02*
X140333Y349833D01*
X140458Y350125D01*
X140500Y350500D01*
X140417Y350875D01*
X140250Y351167D01*
X139958Y351375D01*
X139625Y351417D01*
X139292Y351333D01*
X139083Y351125D01*
X138917Y350833D01*
X138875Y350542D01*
X138917Y350250D01*
X139083Y349875D01*
X138000Y350000D01*
Y351125D01*
G01X127252Y348591D02*
X124752D01*
Y349632D01*
X124877Y349966D01*
X125044Y350174D01*
X125377Y350257D01*
X125710Y350174D01*
X125919Y349924D01*
X126044Y349632D01*
Y348591D01*
G01Y349632D02*
X127252Y350257D01*
G01Y352924D02*
X124752D01*
X126544Y351382D01*
Y353466D01*
G01X124752Y355424D02*
X124835Y355091D01*
X125044Y354841D01*
X125294Y354674D01*
X125627Y354549D01*
X126002Y354507D01*
X126377Y354549D01*
X126710Y354674D01*
X126960Y354841D01*
X127169Y355091D01*
X127252Y355424D01*
X127169Y355757D01*
X126960Y356007D01*
X126710Y356174D01*
X126377Y356299D01*
X126002Y356341D01*
X125627Y356299D01*
X125294Y356174D01*
X125044Y356007D01*
X124835Y355757D01*
X124752Y355424D01*
G01X151500Y294500D02*
Y292000D01*
G01X150542Y294500D02*
X152458D01*
G01X153667Y292000D02*
Y294500D01*
X154667D01*
X155000Y294375D01*
X155250Y294083D01*
X155333Y293750D01*
X155250Y293417D01*
X155042Y293167D01*
X154667Y293042D01*
X153667D01*
G01X156708Y294083D02*
X156958Y294333D01*
X157250Y294458D01*
X157583Y294500D01*
X158000Y294417D01*
X158292Y294208D01*
X158375Y293958D01*
X158333Y293708D01*
X158167Y293500D01*
X157333Y293083D01*
X156958Y292792D01*
X156708Y292375D01*
X156625Y292000D01*
X158375D01*
G01X148700Y297367D02*
X146200D01*
Y298367D01*
X146325Y298700D01*
X146617Y298950D01*
X146950Y299033D01*
X147283Y298950D01*
X147533Y298742D01*
X147658Y298367D01*
Y297367D01*
G01X146408Y302117D02*
X146283Y301867D01*
X146200Y301575D01*
Y301242D01*
X146325Y300867D01*
X146533Y300575D01*
X146783Y300367D01*
X147200Y300200D01*
X147575Y300158D01*
X147950Y300242D01*
X148200Y300367D01*
X148450Y300617D01*
X148617Y300908D01*
X148700Y301200D01*
Y301492D01*
X148617Y301783D01*
X148492Y302033D01*
X148325Y302242D01*
G01X148200Y303283D02*
X148492Y303533D01*
X148658Y303867D01*
X148700Y304242D01*
X148658Y304575D01*
X148450Y304908D01*
X148200Y305117D01*
X147950Y305158D01*
X147658Y305075D01*
X147450Y304783D01*
X147367Y304492D01*
Y304117D01*
G01Y304492D02*
X147242Y304742D01*
X147033Y304950D01*
X146783Y305033D01*
X146533Y304950D01*
X146325Y304742D01*
X146200Y304367D01*
X146242Y303992D01*
X146408Y303617D01*
G01X148700Y307117D02*
X148158Y307200D01*
X147700Y307325D01*
X147283Y307492D01*
X146825Y307700D01*
X146200Y308033D01*
Y306367D01*
G01X156000Y297167D02*
X153500D01*
Y298167D01*
X153625Y298500D01*
X153917Y298750D01*
X154250Y298833D01*
X154583Y298750D01*
X154833Y298542D01*
X154958Y298167D01*
Y297167D01*
G01X153708Y301917D02*
X153583Y301667D01*
X153500Y301375D01*
Y301042D01*
X153625Y300667D01*
X153833Y300375D01*
X154083Y300167D01*
X154500Y300000D01*
X154875Y299958D01*
X155250Y300042D01*
X155500Y300167D01*
X155750Y300417D01*
X155917Y300708D01*
X156000Y301000D01*
Y301292D01*
X155917Y301583D01*
X155792Y301833D01*
X155625Y302042D01*
G01X155500Y303083D02*
X155792Y303333D01*
X155958Y303667D01*
X156000Y304042D01*
X155958Y304375D01*
X155750Y304708D01*
X155500Y304917D01*
X155250Y304958D01*
X154958Y304875D01*
X154750Y304583D01*
X154667Y304292D01*
Y303917D01*
G01Y304292D02*
X154542Y304542D01*
X154333Y304750D01*
X154083Y304833D01*
X153833Y304750D01*
X153625Y304542D01*
X153500Y304167D01*
X153542Y303792D01*
X153708Y303417D01*
G01X156000Y307000D02*
X155958Y307292D01*
X155833Y307625D01*
X155625Y307833D01*
X155333Y307917D01*
X155042Y307833D01*
X154792Y307583D01*
X154667Y307208D01*
Y306792D01*
X154583Y306542D01*
X154375Y306333D01*
X154083Y306250D01*
X153792Y306375D01*
X153583Y306667D01*
X153500Y307000D01*
X153583Y307333D01*
X153792Y307625D01*
X154083Y307750D01*
X154375Y307667D01*
X154583Y307458D01*
X154667Y307208D01*
Y306792D01*
X154792Y306417D01*
X155042Y306167D01*
X155333Y306083D01*
X155625Y306167D01*
X155833Y306375D01*
X155958Y306708D01*
X156000Y307000D01*
G01X156500Y340667D02*
X154000D01*
Y341667D01*
X154125Y342000D01*
X154417Y342250D01*
X154750Y342333D01*
X155083Y342250D01*
X155333Y342042D01*
X155458Y341667D01*
Y340667D01*
G01X154208Y345417D02*
X154083Y345167D01*
X154000Y344875D01*
Y344542D01*
X154125Y344167D01*
X154333Y343875D01*
X154583Y343667D01*
X155000Y343500D01*
X155375Y343458D01*
X155750Y343542D01*
X156000Y343667D01*
X156250Y343917D01*
X156417Y344208D01*
X156500Y344500D01*
Y344792D01*
X156417Y345083D01*
X156292Y345333D01*
X156125Y345542D01*
G01X156000Y346583D02*
X156292Y346833D01*
X156458Y347167D01*
X156500Y347542D01*
X156458Y347875D01*
X156250Y348208D01*
X156000Y348417D01*
X155750Y348458D01*
X155458Y348375D01*
X155250Y348083D01*
X155167Y347792D01*
Y347417D01*
G01Y347792D02*
X155042Y348042D01*
X154833Y348250D01*
X154583Y348333D01*
X154333Y348250D01*
X154125Y348042D01*
X154000Y347667D01*
X154042Y347292D01*
X154208Y346917D01*
G01X156000Y349583D02*
X156292Y349833D01*
X156458Y350167D01*
X156500Y350542D01*
X156458Y350875D01*
X156250Y351208D01*
X156000Y351417D01*
X155750Y351458D01*
X155458Y351375D01*
X155250Y351083D01*
X155167Y350792D01*
Y350417D01*
G01Y350792D02*
X155042Y351042D01*
X154833Y351250D01*
X154583Y351333D01*
X154333Y351250D01*
X154125Y351042D01*
X154000Y350667D01*
X154042Y350292D01*
X154208Y349917D01*
G01X148000Y340667D02*
X145500D01*
Y341667D01*
X145625Y342000D01*
X145917Y342250D01*
X146250Y342333D01*
X146583Y342250D01*
X146833Y342042D01*
X146958Y341667D01*
Y340667D01*
G01X145708Y345417D02*
X145583Y345167D01*
X145500Y344875D01*
Y344542D01*
X145625Y344167D01*
X145833Y343875D01*
X146083Y343667D01*
X146500Y343500D01*
X146875Y343458D01*
X147250Y343542D01*
X147500Y343667D01*
X147750Y343917D01*
X147917Y344208D01*
X148000Y344500D01*
Y344792D01*
X147917Y345083D01*
X147792Y345333D01*
X147625Y345542D01*
G01X147500Y346583D02*
X147792Y346833D01*
X147958Y347167D01*
X148000Y347542D01*
X147958Y347875D01*
X147750Y348208D01*
X147500Y348417D01*
X147250Y348458D01*
X146958Y348375D01*
X146750Y348083D01*
X146667Y347792D01*
Y347417D01*
G01Y347792D02*
X146542Y348042D01*
X146333Y348250D01*
X146083Y348333D01*
X145833Y348250D01*
X145625Y348042D01*
X145500Y347667D01*
X145542Y347292D01*
X145708Y346917D01*
G01X148000Y351000D02*
X145500D01*
X147292Y349458D01*
Y351542D01*
G01X173500Y292167D02*
X171000D01*
Y293167D01*
X171125Y293500D01*
X171417Y293750D01*
X171750Y293833D01*
X172083Y293750D01*
X172333Y293542D01*
X172458Y293167D01*
Y292167D01*
G01X173500Y295167D02*
X171000D01*
Y296208D01*
X171125Y296542D01*
X171292Y296750D01*
X171625Y296833D01*
X171958Y296750D01*
X172167Y296500D01*
X172292Y296208D01*
Y295167D01*
G01Y296208D02*
X173500Y296833D01*
G01X171417Y298208D02*
X171167Y298458D01*
X171042Y298750D01*
X171000Y299083D01*
X171083Y299500D01*
X171292Y299792D01*
X171542Y299875D01*
X171792Y299833D01*
X172000Y299667D01*
X172417Y298833D01*
X172708Y298458D01*
X173125Y298208D01*
X173500Y298125D01*
Y299875D01*
G01X173208Y301292D02*
X173417Y301583D01*
X173500Y301917D01*
X173417Y302250D01*
X173167Y302542D01*
X172792Y302750D01*
X172417Y302833D01*
X171958D01*
X171583Y302750D01*
X171250Y302542D01*
X171083Y302292D01*
X171000Y302000D01*
X171083Y301667D01*
X171250Y301417D01*
X171500Y301250D01*
X171833Y301167D01*
X172125Y301250D01*
X172417Y301458D01*
X172583Y301708D01*
X172625Y302000D01*
X172542Y302333D01*
X172333Y302583D01*
X171958Y302833D01*
G01X162500Y304667D02*
X160000D01*
Y305667D01*
X160125Y306000D01*
X160417Y306250D01*
X160750Y306333D01*
X161083Y306250D01*
X161333Y306042D01*
X161458Y305667D01*
Y304667D01*
G01X160208Y309417D02*
X160083Y309167D01*
X160000Y308875D01*
Y308542D01*
X160125Y308167D01*
X160333Y307875D01*
X160583Y307667D01*
X161000Y307500D01*
X161375Y307458D01*
X161750Y307542D01*
X162000Y307667D01*
X162250Y307917D01*
X162417Y308208D01*
X162500Y308500D01*
Y308792D01*
X162417Y309083D01*
X162292Y309333D01*
X162125Y309542D01*
G01X160417Y310708D02*
X160167Y310958D01*
X160042Y311250D01*
X160000Y311583D01*
X160083Y312000D01*
X160292Y312292D01*
X160542Y312375D01*
X160792Y312333D01*
X161000Y312167D01*
X161417Y311333D01*
X161708Y310958D01*
X162125Y310708D01*
X162500Y310625D01*
Y312375D01*
G01X162208Y313792D02*
X162417Y314083D01*
X162500Y314417D01*
X162417Y314750D01*
X162167Y315042D01*
X161792Y315250D01*
X161417Y315333D01*
X160958D01*
X160583Y315250D01*
X160250Y315042D01*
X160083Y314792D01*
X160000Y314500D01*
X160083Y314167D01*
X160250Y313917D01*
X160500Y313750D01*
X160833Y313667D01*
X161125Y313750D01*
X161417Y313958D01*
X161583Y314208D01*
X161625Y314500D01*
X161542Y314833D01*
X161333Y315083D01*
X160958Y315333D01*
G01X170000Y314667D02*
X167500D01*
Y315667D01*
X167625Y316000D01*
X167917Y316250D01*
X168250Y316333D01*
X168583Y316250D01*
X168833Y316042D01*
X168958Y315667D01*
Y314667D01*
G01X167708Y319417D02*
X167583Y319167D01*
X167500Y318875D01*
Y318542D01*
X167625Y318167D01*
X167833Y317875D01*
X168083Y317667D01*
X168500Y317500D01*
X168875Y317458D01*
X169250Y317542D01*
X169500Y317667D01*
X169750Y317917D01*
X169917Y318208D01*
X170000Y318500D01*
Y318792D01*
X169917Y319083D01*
X169792Y319333D01*
X169625Y319542D01*
G01X169500Y320583D02*
X169792Y320833D01*
X169958Y321167D01*
X170000Y321542D01*
X169958Y321875D01*
X169750Y322208D01*
X169500Y322417D01*
X169250Y322458D01*
X168958Y322375D01*
X168750Y322083D01*
X168667Y321792D01*
Y321417D01*
G01Y321792D02*
X168542Y322042D01*
X168333Y322250D01*
X168083Y322333D01*
X167833Y322250D01*
X167625Y322042D01*
X167500Y321667D01*
X167542Y321292D01*
X167708Y320917D01*
G01X170000Y324500D02*
X167500D01*
X168000Y324000D01*
G01X170000D02*
Y325000D01*
G01X164500Y340667D02*
X162000D01*
Y341667D01*
X162125Y342000D01*
X162417Y342250D01*
X162750Y342333D01*
X163083Y342250D01*
X163333Y342042D01*
X163458Y341667D01*
Y340667D01*
G01X162208Y345417D02*
X162083Y345167D01*
X162000Y344875D01*
Y344542D01*
X162125Y344167D01*
X162333Y343875D01*
X162583Y343667D01*
X163000Y343500D01*
X163375Y343458D01*
X163750Y343542D01*
X164000Y343667D01*
X164250Y343917D01*
X164417Y344208D01*
X164500Y344500D01*
Y344792D01*
X164417Y345083D01*
X164292Y345333D01*
X164125Y345542D01*
G01X164000Y346583D02*
X164292Y346833D01*
X164458Y347167D01*
X164500Y347542D01*
X164458Y347875D01*
X164250Y348208D01*
X164000Y348417D01*
X163750Y348458D01*
X163458Y348375D01*
X163250Y348083D01*
X163167Y347792D01*
Y347417D01*
G01Y347792D02*
X163042Y348042D01*
X162833Y348250D01*
X162583Y348333D01*
X162333Y348250D01*
X162125Y348042D01*
X162000Y347667D01*
X162042Y347292D01*
X162208Y346917D01*
G01X162417Y349708D02*
X162167Y349958D01*
X162042Y350250D01*
X162000Y350583D01*
X162083Y351000D01*
X162292Y351292D01*
X162542Y351375D01*
X162792Y351333D01*
X163000Y351167D01*
X163417Y350333D01*
X163708Y349958D01*
X164125Y349708D01*
X164500Y349625D01*
Y351375D01*
G01X181500Y292667D02*
X179000D01*
Y293667D01*
X179125Y294000D01*
X179417Y294250D01*
X179750Y294333D01*
X180083Y294250D01*
X180333Y294042D01*
X180458Y293667D01*
Y292667D01*
G01X181500Y295667D02*
X179000D01*
Y296708D01*
X179125Y297042D01*
X179292Y297250D01*
X179625Y297333D01*
X179958Y297250D01*
X180167Y297000D01*
X180292Y296708D01*
Y295667D01*
G01Y296708D02*
X181500Y297333D01*
G01X181000Y298583D02*
X181292Y298833D01*
X181458Y299167D01*
X181500Y299542D01*
X181458Y299875D01*
X181250Y300208D01*
X181000Y300417D01*
X180750Y300458D01*
X180458Y300375D01*
X180250Y300083D01*
X180167Y299792D01*
Y299417D01*
G01Y299792D02*
X180042Y300042D01*
X179833Y300250D01*
X179583Y300333D01*
X179333Y300250D01*
X179125Y300042D01*
X179000Y299667D01*
X179042Y299292D01*
X179208Y298917D01*
G01X179417Y301708D02*
X179167Y301958D01*
X179042Y302250D01*
X179000Y302583D01*
X179083Y303000D01*
X179292Y303292D01*
X179542Y303375D01*
X179792Y303333D01*
X180000Y303167D01*
X180417Y302333D01*
X180708Y301958D01*
X181125Y301708D01*
X181500Y301625D01*
Y303375D01*
G01X183167Y290000D02*
Y292500D01*
X184167D01*
X184500Y292375D01*
X184750Y292083D01*
X184833Y291750D01*
X184750Y291417D01*
X184542Y291167D01*
X184167Y291042D01*
X183167D01*
G01X187250Y291250D02*
X188083D01*
Y290500D01*
X187833Y290250D01*
X187542Y290083D01*
X187125Y290000D01*
X186708Y290083D01*
X186417Y290250D01*
X186167Y290500D01*
X186000Y290792D01*
X185917Y291125D01*
Y291417D01*
X186000Y291667D01*
X186167Y291958D01*
X186417Y292208D01*
X186667Y292375D01*
X187000Y292500D01*
X187292D01*
X187625Y292417D01*
X187875Y292250D01*
G01X189083Y290500D02*
X189333Y290208D01*
X189667Y290042D01*
X190042Y290000D01*
X190375Y290042D01*
X190708Y290250D01*
X190917Y290500D01*
X190958Y290750D01*
X190875Y291042D01*
X190583Y291250D01*
X190292Y291333D01*
X189917D01*
G01X190292D02*
X190542Y291458D01*
X190750Y291667D01*
X190833Y291917D01*
X190750Y292167D01*
X190542Y292375D01*
X190167Y292500D01*
X189792Y292458D01*
X189417Y292292D01*
G01X173417Y341000D02*
Y343500D01*
X174417D01*
X174750Y343375D01*
X175000Y343083D01*
X175083Y342750D01*
X175000Y342417D01*
X174792Y342167D01*
X174417Y342042D01*
X173417D01*
G01X176417Y341000D02*
Y343500D01*
X177458D01*
X177792Y343375D01*
X178000Y343208D01*
X178083Y342875D01*
X178000Y342542D01*
X177750Y342333D01*
X177458Y342208D01*
X176417D01*
G01X177458D02*
X178083Y341000D01*
G01X179333Y341500D02*
X179583Y341208D01*
X179917Y341042D01*
X180292Y341000D01*
X180625Y341042D01*
X180958Y341250D01*
X181167Y341500D01*
X181208Y341750D01*
X181125Y342042D01*
X180833Y342250D01*
X180542Y342333D01*
X180167D01*
G01X180542D02*
X180792Y342458D01*
X181000Y342667D01*
X181083Y342917D01*
X181000Y343167D01*
X180792Y343375D01*
X180417Y343500D01*
X180042Y343458D01*
X179667Y343292D01*
G01X182333Y341500D02*
X182583Y341208D01*
X182917Y341042D01*
X183292Y341000D01*
X183625Y341042D01*
X183958Y341250D01*
X184167Y341500D01*
X184208Y341750D01*
X184125Y342042D01*
X183833Y342250D01*
X183542Y342333D01*
X183167D01*
G01X183542D02*
X183792Y342458D01*
X184000Y342667D01*
X184083Y342917D01*
X184000Y343167D01*
X183792Y343375D01*
X183417Y343500D01*
X183042Y343458D01*
X182667Y343292D01*
G01X175667Y334000D02*
Y336500D01*
X176667D01*
X177000Y336375D01*
X177250Y336083D01*
X177333Y335750D01*
X177250Y335417D01*
X177042Y335167D01*
X176667Y335042D01*
X175667D01*
G01X178583Y336500D02*
Y334708D01*
X178750Y334333D01*
X179083Y334083D01*
X179500Y334000D01*
X179917Y334083D01*
X180250Y334333D01*
X180417Y334708D01*
Y336500D01*
G01X182500Y334000D02*
Y336500D01*
X182000Y336000D01*
G01Y334000D02*
X183000D01*
G01X192667Y290000D02*
Y292500D01*
X193667D01*
X194000Y292375D01*
X194250Y292083D01*
X194333Y291750D01*
X194250Y291417D01*
X194042Y291167D01*
X193667Y291042D01*
X192667D01*
G01X195667Y290000D02*
Y292500D01*
X196708D01*
X197042Y292375D01*
X197250Y292208D01*
X197333Y291875D01*
X197250Y291542D01*
X197000Y291333D01*
X196708Y291208D01*
X195667D01*
G01X196708D02*
X197333Y290000D01*
G01X198583Y290500D02*
X198833Y290208D01*
X199167Y290042D01*
X199542Y290000D01*
X199875Y290042D01*
X200208Y290250D01*
X200417Y290500D01*
X200458Y290750D01*
X200375Y291042D01*
X200083Y291250D01*
X199792Y291333D01*
X199417D01*
G01X199792D02*
X200042Y291458D01*
X200250Y291667D01*
X200333Y291917D01*
X200250Y292167D01*
X200042Y292375D01*
X199667Y292500D01*
X199292Y292458D01*
X198917Y292292D01*
G01X202417Y290000D02*
X202500Y290542D01*
X202625Y291000D01*
X202792Y291417D01*
X203000Y291875D01*
X203333Y292500D01*
X201667D01*
G01X194667Y344500D02*
Y347000D01*
X195667D01*
X196000Y346875D01*
X196250Y346583D01*
X196333Y346250D01*
X196250Y345917D01*
X196042Y345667D01*
X195667Y345542D01*
X194667D01*
G01X199417Y346792D02*
X199167Y346917D01*
X198875Y347000D01*
X198542D01*
X198167Y346875D01*
X197875Y346667D01*
X197667Y346417D01*
X197500Y346000D01*
X197458Y345625D01*
X197542Y345250D01*
X197667Y345000D01*
X197917Y344750D01*
X198208Y344583D01*
X198500Y344500D01*
X198792D01*
X199083Y344583D01*
X199333Y344708D01*
X199542Y344875D01*
G01X200583Y345000D02*
X200833Y344708D01*
X201167Y344542D01*
X201542Y344500D01*
X201875Y344542D01*
X202208Y344750D01*
X202417Y345000D01*
X202458Y345250D01*
X202375Y345542D01*
X202083Y345750D01*
X201792Y345833D01*
X201417D01*
G01X201792D02*
X202042Y345958D01*
X202250Y346167D01*
X202333Y346417D01*
X202250Y346667D01*
X202042Y346875D01*
X201667Y347000D01*
X201292Y346958D01*
X200917Y346792D01*
G01X204500Y347000D02*
X204167Y346917D01*
X203917Y346708D01*
X203750Y346458D01*
X203625Y346125D01*
X203583Y345750D01*
X203625Y345375D01*
X203750Y345042D01*
X203917Y344792D01*
X204167Y344583D01*
X204500Y344500D01*
X204833Y344583D01*
X205083Y344792D01*
X205250Y345042D01*
X205375Y345375D01*
X205417Y345750D01*
X205375Y346125D01*
X205250Y346458D01*
X205083Y346708D01*
X204833Y346917D01*
X204500Y347000D01*
G01X220000Y292667D02*
X217500D01*
Y293667D01*
X217625Y294000D01*
X217917Y294250D01*
X218250Y294333D01*
X218583Y294250D01*
X218833Y294042D01*
X218958Y293667D01*
Y292667D01*
G01X220000Y295667D02*
X217500D01*
Y296708D01*
X217625Y297042D01*
X217792Y297250D01*
X218125Y297333D01*
X218458Y297250D01*
X218667Y297000D01*
X218792Y296708D01*
Y295667D01*
G01Y296708D02*
X220000Y297333D01*
G01X219500Y298583D02*
X219792Y298833D01*
X219958Y299167D01*
X220000Y299542D01*
X219958Y299875D01*
X219750Y300208D01*
X219500Y300417D01*
X219250Y300458D01*
X218958Y300375D01*
X218750Y300083D01*
X218667Y299792D01*
Y299417D01*
G01Y299792D02*
X218542Y300042D01*
X218333Y300250D01*
X218083Y300333D01*
X217833Y300250D01*
X217625Y300042D01*
X217500Y299667D01*
X217542Y299292D01*
X217708Y298917D01*
G01X219708Y301792D02*
X219917Y302083D01*
X220000Y302417D01*
X219917Y302750D01*
X219667Y303042D01*
X219292Y303250D01*
X218917Y303333D01*
X218458D01*
X218083Y303250D01*
X217750Y303042D01*
X217583Y302792D01*
X217500Y302500D01*
X217583Y302167D01*
X217750Y301917D01*
X218000Y301750D01*
X218333Y301667D01*
X218625Y301750D01*
X218917Y301958D01*
X219083Y302208D01*
X219125Y302500D01*
X219042Y302833D01*
X218833Y303083D01*
X218458Y303333D01*
G01X216167Y341500D02*
Y344000D01*
X217167D01*
X217500Y343875D01*
X217750Y343583D01*
X217833Y343250D01*
X217750Y342917D01*
X217542Y342667D01*
X217167Y342542D01*
X216167D01*
G01X219167Y344000D02*
Y341500D01*
X220833D01*
G01X222083Y342000D02*
X222333Y341708D01*
X222667Y341542D01*
X223042Y341500D01*
X223375Y341542D01*
X223708Y341750D01*
X223917Y342000D01*
X223958Y342250D01*
X223875Y342542D01*
X223583Y342750D01*
X223292Y342833D01*
X222917D01*
G01X223292D02*
X223542Y342958D01*
X223750Y343167D01*
X223833Y343417D01*
X223750Y343667D01*
X223542Y343875D01*
X223167Y344000D01*
X222792Y343958D01*
X222417Y343792D01*
G01X234625Y35000D02*
Y37500D01*
G01X236375D02*
Y35000D01*
G01Y36250D02*
X234625D01*
G01X237583Y35500D02*
X237833Y35208D01*
X238167Y35042D01*
X238542Y35000D01*
X238875Y35042D01*
X239208Y35250D01*
X239417Y35500D01*
X239458Y35750D01*
X239375Y36042D01*
X239083Y36250D01*
X238792Y36333D01*
X238417D01*
G01X238792D02*
X239042Y36458D01*
X239250Y36667D01*
X239333Y36917D01*
X239250Y37167D01*
X239042Y37375D01*
X238667Y37500D01*
X238292Y37458D01*
X237917Y37292D01*
G01X233417Y53792D02*
X233167Y53917D01*
X232875Y54000D01*
X232542D01*
X232167Y53875D01*
X231875Y53667D01*
X231667Y53417D01*
X231500Y53000D01*
X231458Y52625D01*
X231542Y52250D01*
X231667Y52000D01*
X231917Y51750D01*
X232208Y51583D01*
X232500Y51500D01*
X232792D01*
X233083Y51583D01*
X233333Y51708D01*
X233542Y51875D01*
G01X234708Y53583D02*
X234958Y53833D01*
X235250Y53958D01*
X235583Y54000D01*
X236000Y53917D01*
X236292Y53708D01*
X236375Y53458D01*
X236333Y53208D01*
X236167Y53000D01*
X235333Y52583D01*
X234958Y52292D01*
X234708Y51875D01*
X234625Y51500D01*
X236375D01*
G01X238500D02*
Y54000D01*
X238000Y53500D01*
G01Y51500D02*
X239000D01*
G01X233417Y63792D02*
X233167Y63917D01*
X232875Y64000D01*
X232542D01*
X232167Y63875D01*
X231875Y63667D01*
X231667Y63417D01*
X231500Y63000D01*
X231458Y62625D01*
X231542Y62250D01*
X231667Y62000D01*
X231917Y61750D01*
X232208Y61583D01*
X232500Y61500D01*
X232792D01*
X233083Y61583D01*
X233333Y61708D01*
X233542Y61875D01*
G01X234708Y63583D02*
X234958Y63833D01*
X235250Y63958D01*
X235583Y64000D01*
X236000Y63917D01*
X236292Y63708D01*
X236375Y63458D01*
X236333Y63208D01*
X236167Y63000D01*
X235333Y62583D01*
X234958Y62292D01*
X234708Y61875D01*
X234625Y61500D01*
X236375D01*
G01X237708Y63583D02*
X237958Y63833D01*
X238250Y63958D01*
X238583Y64000D01*
X239000Y63917D01*
X239292Y63708D01*
X239375Y63458D01*
X239333Y63208D01*
X239167Y63000D01*
X238333Y62583D01*
X237958Y62292D01*
X237708Y61875D01*
X237625Y61500D01*
X239375D01*
G01X233417Y58792D02*
X233167Y58917D01*
X232875Y59000D01*
X232542D01*
X232167Y58875D01*
X231875Y58667D01*
X231667Y58417D01*
X231500Y58000D01*
X231458Y57625D01*
X231542Y57250D01*
X231667Y57000D01*
X231917Y56750D01*
X232208Y56583D01*
X232500Y56500D01*
X232792D01*
X233083Y56583D01*
X233333Y56708D01*
X233542Y56875D01*
G01X234708Y58583D02*
X234958Y58833D01*
X235250Y58958D01*
X235583Y59000D01*
X236000Y58917D01*
X236292Y58708D01*
X236375Y58458D01*
X236333Y58208D01*
X236167Y58000D01*
X235333Y57583D01*
X234958Y57292D01*
X234708Y56875D01*
X234625Y56500D01*
X236375D01*
G01X238500Y59000D02*
X238167Y58917D01*
X237917Y58708D01*
X237750Y58458D01*
X237625Y58125D01*
X237583Y57750D01*
X237625Y57375D01*
X237750Y57042D01*
X237917Y56792D01*
X238167Y56583D01*
X238500Y56500D01*
X238833Y56583D01*
X239083Y56792D01*
X239250Y57042D01*
X239375Y57375D01*
X239417Y57750D01*
X239375Y58125D01*
X239250Y58458D01*
X239083Y58708D01*
X238833Y58917D01*
X238500Y59000D01*
G01X224417Y131292D02*
X224167Y131417D01*
X223875Y131500D01*
X223542D01*
X223167Y131375D01*
X222875Y131167D01*
X222667Y130917D01*
X222500Y130500D01*
X222458Y130125D01*
X222542Y129750D01*
X222667Y129500D01*
X222917Y129250D01*
X223208Y129083D01*
X223500Y129000D01*
X223792D01*
X224083Y129083D01*
X224333Y129208D01*
X224542Y129375D01*
G01X225583Y129500D02*
X225833Y129208D01*
X226167Y129042D01*
X226542Y129000D01*
X226875Y129042D01*
X227208Y129250D01*
X227417Y129500D01*
X227458Y129750D01*
X227375Y130042D01*
X227083Y130250D01*
X226792Y130333D01*
X226417D01*
G01X226792D02*
X227042Y130458D01*
X227250Y130667D01*
X227333Y130917D01*
X227250Y131167D01*
X227042Y131375D01*
X226667Y131500D01*
X226292Y131458D01*
X225917Y131292D01*
G01X230000Y129000D02*
Y131500D01*
X228458Y129708D01*
X230542D01*
G01X224417Y123292D02*
X224167Y123417D01*
X223875Y123500D01*
X223542D01*
X223167Y123375D01*
X222875Y123167D01*
X222667Y122917D01*
X222500Y122500D01*
X222458Y122125D01*
X222542Y121750D01*
X222667Y121500D01*
X222917Y121250D01*
X223208Y121083D01*
X223500Y121000D01*
X223792D01*
X224083Y121083D01*
X224333Y121208D01*
X224542Y121375D01*
G01X225583Y121500D02*
X225833Y121208D01*
X226167Y121042D01*
X226542Y121000D01*
X226875Y121042D01*
X227208Y121250D01*
X227417Y121500D01*
X227458Y121750D01*
X227375Y122042D01*
X227083Y122250D01*
X226792Y122333D01*
X226417D01*
G01X226792D02*
X227042Y122458D01*
X227250Y122667D01*
X227333Y122917D01*
X227250Y123167D01*
X227042Y123375D01*
X226667Y123500D01*
X226292Y123458D01*
X225917Y123292D01*
G01X229500Y121000D02*
X229792Y121042D01*
X230125Y121167D01*
X230333Y121375D01*
X230417Y121667D01*
X230333Y121958D01*
X230083Y122208D01*
X229708Y122333D01*
X229292D01*
X229042Y122417D01*
X228833Y122625D01*
X228750Y122917D01*
X228875Y123208D01*
X229167Y123417D01*
X229500Y123500D01*
X229833Y123417D01*
X230125Y123208D01*
X230250Y122917D01*
X230167Y122625D01*
X229958Y122417D01*
X229708Y122333D01*
X229292D01*
X228917Y122208D01*
X228667Y121958D01*
X228583Y121667D01*
X228667Y121375D01*
X228875Y121167D01*
X229208Y121042D01*
X229500Y121000D01*
G01X224417Y127292D02*
X224167Y127417D01*
X223875Y127500D01*
X223542D01*
X223167Y127375D01*
X222875Y127167D01*
X222667Y126917D01*
X222500Y126500D01*
X222458Y126125D01*
X222542Y125750D01*
X222667Y125500D01*
X222917Y125250D01*
X223208Y125083D01*
X223500Y125000D01*
X223792D01*
X224083Y125083D01*
X224333Y125208D01*
X224542Y125375D01*
G01X225583Y125500D02*
X225833Y125208D01*
X226167Y125042D01*
X226542Y125000D01*
X226875Y125042D01*
X227208Y125250D01*
X227417Y125500D01*
X227458Y125750D01*
X227375Y126042D01*
X227083Y126250D01*
X226792Y126333D01*
X226417D01*
G01X226792D02*
X227042Y126458D01*
X227250Y126667D01*
X227333Y126917D01*
X227250Y127167D01*
X227042Y127375D01*
X226667Y127500D01*
X226292Y127458D01*
X225917Y127292D01*
G01X229417Y125000D02*
X229500Y125542D01*
X229625Y126000D01*
X229792Y126417D01*
X230000Y126875D01*
X230333Y127500D01*
X228667D01*
G01X224417Y139292D02*
X224167Y139417D01*
X223875Y139500D01*
X223542D01*
X223167Y139375D01*
X222875Y139167D01*
X222667Y138917D01*
X222500Y138500D01*
X222458Y138125D01*
X222542Y137750D01*
X222667Y137500D01*
X222917Y137250D01*
X223208Y137083D01*
X223500Y137000D01*
X223792D01*
X224083Y137083D01*
X224333Y137208D01*
X224542Y137375D01*
G01X225583Y137500D02*
X225833Y137208D01*
X226167Y137042D01*
X226542Y137000D01*
X226875Y137042D01*
X227208Y137250D01*
X227417Y137500D01*
X227458Y137750D01*
X227375Y138042D01*
X227083Y138250D01*
X226792Y138333D01*
X226417D01*
G01X226792D02*
X227042Y138458D01*
X227250Y138667D01*
X227333Y138917D01*
X227250Y139167D01*
X227042Y139375D01*
X226667Y139500D01*
X226292Y139458D01*
X225917Y139292D01*
G01X228708Y139083D02*
X228958Y139333D01*
X229250Y139458D01*
X229583Y139500D01*
X230000Y139417D01*
X230292Y139208D01*
X230375Y138958D01*
X230333Y138708D01*
X230167Y138500D01*
X229333Y138083D01*
X228958Y137792D01*
X228708Y137375D01*
X228625Y137000D01*
X230375D01*
G01X224417Y135292D02*
X224167Y135417D01*
X223875Y135500D01*
X223542D01*
X223167Y135375D01*
X222875Y135167D01*
X222667Y134917D01*
X222500Y134500D01*
X222458Y134125D01*
X222542Y133750D01*
X222667Y133500D01*
X222917Y133250D01*
X223208Y133083D01*
X223500Y133000D01*
X223792D01*
X224083Y133083D01*
X224333Y133208D01*
X224542Y133375D01*
G01X225583Y133500D02*
X225833Y133208D01*
X226167Y133042D01*
X226542Y133000D01*
X226875Y133042D01*
X227208Y133250D01*
X227417Y133500D01*
X227458Y133750D01*
X227375Y134042D01*
X227083Y134250D01*
X226792Y134333D01*
X226417D01*
G01X226792D02*
X227042Y134458D01*
X227250Y134667D01*
X227333Y134917D01*
X227250Y135167D01*
X227042Y135375D01*
X226667Y135500D01*
X226292Y135458D01*
X225917Y135292D01*
G01X228583Y133500D02*
X228833Y133208D01*
X229167Y133042D01*
X229542Y133000D01*
X229875Y133042D01*
X230208Y133250D01*
X230417Y133500D01*
X230458Y133750D01*
X230375Y134042D01*
X230083Y134250D01*
X229792Y134333D01*
X229417D01*
G01X229792D02*
X230042Y134458D01*
X230250Y134667D01*
X230333Y134917D01*
X230250Y135167D01*
X230042Y135375D01*
X229667Y135500D01*
X229292Y135458D01*
X228917Y135292D01*
G01X236583Y170000D02*
Y168208D01*
X236750Y167833D01*
X237083Y167583D01*
X237500Y167500D01*
X237917Y167583D01*
X238250Y167833D01*
X238417Y168208D01*
Y170000D01*
G01X240500Y167500D02*
Y170000D01*
X240000Y169500D01*
G01Y167500D02*
X241000D01*
G01X224267Y181142D02*
X224017Y181267D01*
X223725Y181350D01*
X223392D01*
X223017Y181225D01*
X222725Y181017D01*
X222517Y180767D01*
X222350Y180350D01*
X222308Y179975D01*
X222392Y179600D01*
X222517Y179350D01*
X222767Y179100D01*
X223058Y178933D01*
X223350Y178850D01*
X223642D01*
X223933Y178933D01*
X224183Y179058D01*
X224392Y179225D01*
G01X225433Y179350D02*
X225683Y179058D01*
X226017Y178892D01*
X226392Y178850D01*
X226725Y178892D01*
X227058Y179100D01*
X227267Y179350D01*
X227308Y179600D01*
X227225Y179892D01*
X226933Y180100D01*
X226642Y180183D01*
X226267D01*
G01X226642D02*
X226892Y180308D01*
X227100Y180517D01*
X227183Y180767D01*
X227100Y181017D01*
X226892Y181225D01*
X226517Y181350D01*
X226142Y181308D01*
X225767Y181142D01*
G01X224417Y177292D02*
X224167Y177417D01*
X223875Y177500D01*
X223542D01*
X223167Y177375D01*
X222875Y177167D01*
X222667Y176917D01*
X222500Y176500D01*
X222458Y176125D01*
X222542Y175750D01*
X222667Y175500D01*
X222917Y175250D01*
X223208Y175083D01*
X223500Y175000D01*
X223792D01*
X224083Y175083D01*
X224333Y175208D01*
X224542Y175375D01*
G01X226500Y175000D02*
Y177500D01*
X226000Y177000D01*
G01Y175000D02*
X227000D01*
G01X224267Y184642D02*
X224017Y184767D01*
X223725Y184850D01*
X223392D01*
X223017Y184725D01*
X222725Y184517D01*
X222517Y184267D01*
X222350Y183850D01*
X222308Y183475D01*
X222392Y183100D01*
X222517Y182850D01*
X222767Y182600D01*
X223058Y182433D01*
X223350Y182350D01*
X223642D01*
X223933Y182433D01*
X224183Y182558D01*
X224392Y182725D01*
G01X225558Y184433D02*
X225808Y184683D01*
X226100Y184808D01*
X226433Y184850D01*
X226850Y184767D01*
X227142Y184558D01*
X227225Y184308D01*
X227183Y184058D01*
X227017Y183850D01*
X226183Y183433D01*
X225808Y183142D01*
X225558Y182725D01*
X225475Y182350D01*
X227225D01*
G01X224267Y239642D02*
X224017Y239767D01*
X223725Y239850D01*
X223392D01*
X223017Y239725D01*
X222725Y239517D01*
X222517Y239267D01*
X222350Y238850D01*
X222308Y238475D01*
X222392Y238100D01*
X222517Y237850D01*
X222767Y237600D01*
X223058Y237433D01*
X223350Y237350D01*
X223642D01*
X223933Y237433D01*
X224183Y237558D01*
X224392Y237725D01*
G01X226350Y237350D02*
Y239850D01*
X225850Y239350D01*
G01Y237350D02*
X226850D01*
G01X228433Y237725D02*
X228683Y237517D01*
X228975Y237392D01*
X229350Y237350D01*
X229725Y237433D01*
X230017Y237600D01*
X230225Y237892D01*
X230267Y238225D01*
X230183Y238558D01*
X229975Y238767D01*
X229683Y238933D01*
X229392Y238975D01*
X229100Y238933D01*
X228725Y238767D01*
X228850Y239850D01*
X229975D01*
G01X224267Y244642D02*
X224017Y244767D01*
X223725Y244850D01*
X223392D01*
X223017Y244725D01*
X222725Y244517D01*
X222517Y244267D01*
X222350Y243850D01*
X222308Y243475D01*
X222392Y243100D01*
X222517Y242850D01*
X222767Y242600D01*
X223058Y242433D01*
X223350Y242350D01*
X223642D01*
X223933Y242433D01*
X224183Y242558D01*
X224392Y242725D01*
G01X226350Y242350D02*
Y244850D01*
X225850Y244350D01*
G01Y242350D02*
X226850D01*
G01X229850D02*
Y244850D01*
X228308Y243058D01*
X230392D01*
G01X224767Y231642D02*
X224517Y231767D01*
X224225Y231850D01*
X223892D01*
X223517Y231725D01*
X223225Y231517D01*
X223017Y231267D01*
X222850Y230850D01*
X222808Y230475D01*
X222892Y230100D01*
X223017Y229850D01*
X223267Y229600D01*
X223558Y229433D01*
X223850Y229350D01*
X224142D01*
X224433Y229433D01*
X224683Y229558D01*
X224892Y229725D01*
G01X226850Y229350D02*
Y231850D01*
X226350Y231350D01*
G01Y229350D02*
X227350D01*
G01X229142Y229642D02*
X229433Y229433D01*
X229767Y229350D01*
X230100Y229433D01*
X230392Y229683D01*
X230600Y230058D01*
X230683Y230433D01*
Y230892D01*
X230600Y231267D01*
X230392Y231600D01*
X230142Y231767D01*
X229850Y231850D01*
X229517Y231767D01*
X229267Y231600D01*
X229100Y231350D01*
X229017Y231017D01*
X229100Y230725D01*
X229308Y230433D01*
X229558Y230267D01*
X229850Y230225D01*
X230183Y230308D01*
X230433Y230517D01*
X230683Y230892D01*
G01X224767Y235642D02*
X224517Y235767D01*
X224225Y235850D01*
X223892D01*
X223517Y235725D01*
X223225Y235517D01*
X223017Y235267D01*
X222850Y234850D01*
X222808Y234475D01*
X222892Y234100D01*
X223017Y233850D01*
X223267Y233600D01*
X223558Y233433D01*
X223850Y233350D01*
X224142D01*
X224433Y233433D01*
X224683Y233558D01*
X224892Y233725D01*
G01X226850Y233350D02*
Y235850D01*
X226350Y235350D01*
G01Y233350D02*
X227350D01*
G01X229850D02*
X230142Y233392D01*
X230475Y233517D01*
X230683Y233725D01*
X230767Y234017D01*
X230683Y234308D01*
X230433Y234558D01*
X230058Y234683D01*
X229642D01*
X229392Y234767D01*
X229183Y234975D01*
X229100Y235267D01*
X229225Y235558D01*
X229517Y235767D01*
X229850Y235850D01*
X230183Y235767D01*
X230475Y235558D01*
X230600Y235267D01*
X230517Y234975D01*
X230308Y234767D01*
X230058Y234683D01*
X229642D01*
X229267Y234558D01*
X229017Y234308D01*
X228933Y234017D01*
X229017Y233725D01*
X229225Y233517D01*
X229558Y233392D01*
X229850Y233350D01*
G01X224767Y248142D02*
X224517Y248267D01*
X224225Y248350D01*
X223892D01*
X223517Y248225D01*
X223225Y248017D01*
X223017Y247767D01*
X222850Y247350D01*
X222808Y246975D01*
X222892Y246600D01*
X223017Y246350D01*
X223267Y246100D01*
X223558Y245933D01*
X223850Y245850D01*
X224142D01*
X224433Y245933D01*
X224683Y246058D01*
X224892Y246225D01*
G01X226850Y245850D02*
Y248350D01*
X226350Y247850D01*
G01Y245850D02*
X227350D01*
G01X228933Y246350D02*
X229183Y246058D01*
X229517Y245892D01*
X229892Y245850D01*
X230225Y245892D01*
X230558Y246100D01*
X230767Y246350D01*
X230808Y246600D01*
X230725Y246892D01*
X230433Y247100D01*
X230142Y247183D01*
X229767D01*
G01X230142D02*
X230392Y247308D01*
X230600Y247517D01*
X230683Y247767D01*
X230600Y248017D01*
X230392Y248225D01*
X230017Y248350D01*
X229642Y248308D01*
X229267Y248142D01*
G01X225667Y292500D02*
Y295000D01*
X226667D01*
X227000Y294875D01*
X227250Y294583D01*
X227333Y294250D01*
X227250Y293917D01*
X227042Y293667D01*
X226667Y293542D01*
X225667D01*
G01X228667Y292500D02*
Y295000D01*
X229708D01*
X230042Y294875D01*
X230250Y294708D01*
X230333Y294375D01*
X230250Y294042D01*
X230000Y293833D01*
X229708Y293708D01*
X228667D01*
G01X229708D02*
X230333Y292500D01*
G01X231708Y294583D02*
X231958Y294833D01*
X232250Y294958D01*
X232583Y295000D01*
X233000Y294917D01*
X233292Y294708D01*
X233375Y294458D01*
X233333Y294208D01*
X233167Y294000D01*
X232333Y293583D01*
X231958Y293292D01*
X231708Y292875D01*
X231625Y292500D01*
X233375D01*
G01X235417D02*
X235500Y293042D01*
X235625Y293500D01*
X235792Y293917D01*
X236000Y294375D01*
X236333Y295000D01*
X234667D01*
G01X221708Y294417D02*
X221583Y294167D01*
X221500Y293875D01*
Y293542D01*
X221625Y293167D01*
X221833Y292875D01*
X222083Y292667D01*
X222500Y292500D01*
X222875Y292458D01*
X223250Y292542D01*
X223500Y292667D01*
X223750Y292917D01*
X223917Y293208D01*
X224000Y293500D01*
Y293792D01*
X223917Y294083D01*
X223792Y294333D01*
X223625Y294542D01*
G01X221917Y295708D02*
X221667Y295958D01*
X221542Y296250D01*
X221500Y296583D01*
X221583Y297000D01*
X221792Y297292D01*
X222042Y297375D01*
X222292Y297333D01*
X222500Y297167D01*
X222917Y296333D01*
X223208Y295958D01*
X223625Y295708D01*
X224000Y295625D01*
Y297375D01*
G01X222958Y298708D02*
X222667Y299000D01*
X222500Y299250D01*
X222417Y299583D01*
X222500Y299875D01*
X222667Y300083D01*
X222917Y300250D01*
X223208Y300292D01*
X223458Y300250D01*
X223708Y300083D01*
X223917Y299833D01*
X224000Y299542D01*
X223917Y299208D01*
X223667Y298917D01*
X223292Y298750D01*
X222875Y298708D01*
X222333Y298792D01*
X222042Y298917D01*
X221750Y299125D01*
X221542Y299417D01*
X221500Y299708D01*
X221583Y300000D01*
X221792Y300208D01*
G01X224000Y302417D02*
X223458Y302500D01*
X223000Y302625D01*
X222583Y302792D01*
X222125Y303000D01*
X221500Y303333D01*
Y301667D01*
G01X225667Y300500D02*
Y303000D01*
X226667D01*
X227000Y302875D01*
X227250Y302583D01*
X227333Y302250D01*
X227250Y301917D01*
X227042Y301667D01*
X226667Y301542D01*
X225667D01*
G01X228667Y300500D02*
Y303000D01*
X229708D01*
X230042Y302875D01*
X230250Y302708D01*
X230333Y302375D01*
X230250Y302042D01*
X230000Y301833D01*
X229708Y301708D01*
X228667D01*
G01X229708D02*
X230333Y300500D01*
G01X232500D02*
Y303000D01*
X232000Y302500D01*
G01Y300500D02*
X233000D01*
G01X225667Y296500D02*
Y299000D01*
X226667D01*
X227000Y298875D01*
X227250Y298583D01*
X227333Y298250D01*
X227250Y297917D01*
X227042Y297667D01*
X226667Y297542D01*
X225667D01*
G01X230417Y298792D02*
X230167Y298917D01*
X229875Y299000D01*
X229542D01*
X229167Y298875D01*
X228875Y298667D01*
X228667Y298417D01*
X228500Y298000D01*
X228458Y297625D01*
X228542Y297250D01*
X228667Y297000D01*
X228917Y296750D01*
X229208Y296583D01*
X229500Y296500D01*
X229792D01*
X230083Y296583D01*
X230333Y296708D01*
X230542Y296875D01*
G01X233000Y296500D02*
Y299000D01*
X231458Y297208D01*
X233542D01*
G01X234583Y297000D02*
X234833Y296708D01*
X235167Y296542D01*
X235542Y296500D01*
X235875Y296542D01*
X236208Y296750D01*
X236417Y297000D01*
X236458Y297250D01*
X236375Y297542D01*
X236083Y297750D01*
X235792Y297833D01*
X235417D01*
G01X235792D02*
X236042Y297958D01*
X236250Y298167D01*
X236333Y298417D01*
X236250Y298667D01*
X236042Y298875D01*
X235667Y299000D01*
X235292Y298958D01*
X234917Y298792D01*
G01X240917Y147292D02*
X240667Y147417D01*
X240375Y147500D01*
X240042D01*
X239667Y147375D01*
X239375Y147167D01*
X239167Y146917D01*
X239000Y146500D01*
X238958Y146125D01*
X239042Y145750D01*
X239167Y145500D01*
X239417Y145250D01*
X239708Y145083D01*
X240000Y145000D01*
X240292D01*
X240583Y145083D01*
X240833Y145208D01*
X241042Y145375D01*
G01X242083Y145500D02*
X242333Y145208D01*
X242667Y145042D01*
X243042Y145000D01*
X243375Y145042D01*
X243708Y145250D01*
X243917Y145500D01*
X243958Y145750D01*
X243875Y146042D01*
X243583Y146250D01*
X243292Y146333D01*
X242917D01*
G01X243292D02*
X243542Y146458D01*
X243750Y146667D01*
X243833Y146917D01*
X243750Y147167D01*
X243542Y147375D01*
X243167Y147500D01*
X242792Y147458D01*
X242417Y147292D01*
G01X246000Y145000D02*
Y147500D01*
X245500Y147000D01*
G01Y145000D02*
X246500D01*
G01X243708Y252917D02*
X243583Y252667D01*
X243500Y252375D01*
Y252042D01*
X243625Y251667D01*
X243833Y251375D01*
X244083Y251167D01*
X244500Y251000D01*
X244875Y250958D01*
X245250Y251042D01*
X245500Y251167D01*
X245750Y251417D01*
X245917Y251708D01*
X246000Y252000D01*
Y252292D01*
X245917Y252583D01*
X245792Y252833D01*
X245625Y253042D01*
G01X246000Y255000D02*
X243500D01*
X244000Y254500D01*
G01X246000D02*
Y255500D01*
G01X243917Y257208D02*
X243667Y257458D01*
X243542Y257750D01*
X243500Y258083D01*
X243583Y258500D01*
X243792Y258792D01*
X244042Y258875D01*
X244292Y258833D01*
X244500Y258667D01*
X244917Y257833D01*
X245208Y257458D01*
X245625Y257208D01*
X246000Y257125D01*
Y258875D01*
G01X243667Y348500D02*
Y351000D01*
X244667D01*
X245000Y350875D01*
X245250Y350583D01*
X245333Y350250D01*
X245250Y349917D01*
X245042Y349667D01*
X244667Y349542D01*
X243667D01*
G01X248417Y350792D02*
X248167Y350917D01*
X247875Y351000D01*
X247542D01*
X247167Y350875D01*
X246875Y350667D01*
X246667Y350417D01*
X246500Y350000D01*
X246458Y349625D01*
X246542Y349250D01*
X246667Y349000D01*
X246917Y348750D01*
X247208Y348583D01*
X247500Y348500D01*
X247792D01*
X248083Y348583D01*
X248333Y348708D01*
X248542Y348875D01*
G01X251000Y348500D02*
Y351000D01*
X249458Y349208D01*
X251542D01*
G01X252583Y348875D02*
X252833Y348667D01*
X253125Y348542D01*
X253500Y348500D01*
X253875Y348583D01*
X254167Y348750D01*
X254375Y349042D01*
X254417Y349375D01*
X254333Y349708D01*
X254125Y349917D01*
X253833Y350083D01*
X253542Y350125D01*
X253250Y350083D01*
X252875Y349917D01*
X253000Y351000D01*
X254125D01*
G01X263000Y161500D02*
Y159000D01*
G01X262042Y161500D02*
X263958D01*
G01X265167Y159000D02*
Y161500D01*
X266167D01*
X266500Y161375D01*
X266750Y161083D01*
X266833Y160750D01*
X266750Y160417D01*
X266542Y160167D01*
X266167Y160042D01*
X265167D01*
G01X269000Y159000D02*
Y161500D01*
X268500Y161000D01*
G01Y159000D02*
X269500D01*
G01X266467Y294700D02*
Y297200D01*
X267467D01*
X267800Y297075D01*
X268050Y296783D01*
X268133Y296450D01*
X268050Y296117D01*
X267842Y295867D01*
X267467Y295742D01*
X266467D01*
G01X271217Y296992D02*
X270967Y297117D01*
X270675Y297200D01*
X270342D01*
X269967Y297075D01*
X269675Y296867D01*
X269467Y296617D01*
X269300Y296200D01*
X269258Y295825D01*
X269342Y295450D01*
X269467Y295200D01*
X269717Y294950D01*
X270008Y294783D01*
X270300Y294700D01*
X270592D01*
X270883Y294783D01*
X271133Y294908D01*
X271342Y295075D01*
G01X273800Y294700D02*
Y297200D01*
X272258Y295408D01*
X274342D01*
G01X275508Y296783D02*
X275758Y297033D01*
X276050Y297158D01*
X276383Y297200D01*
X276800Y297117D01*
X277092Y296908D01*
X277175Y296658D01*
X277133Y296408D01*
X276967Y296200D01*
X276133Y295783D01*
X275758Y295492D01*
X275508Y295075D01*
X275425Y294700D01*
X277175D01*
G01X266467Y302700D02*
Y305200D01*
X267467D01*
X267800Y305075D01*
X268050Y304783D01*
X268133Y304450D01*
X268050Y304117D01*
X267842Y303867D01*
X267467Y303742D01*
X266467D01*
G01X271217Y304992D02*
X270967Y305117D01*
X270675Y305200D01*
X270342D01*
X269967Y305075D01*
X269675Y304867D01*
X269467Y304617D01*
X269300Y304200D01*
X269258Y303825D01*
X269342Y303450D01*
X269467Y303200D01*
X269717Y302950D01*
X270008Y302783D01*
X270300Y302700D01*
X270592D01*
X270883Y302783D01*
X271133Y302908D01*
X271342Y303075D01*
G01X272383Y303200D02*
X272633Y302908D01*
X272967Y302742D01*
X273342Y302700D01*
X273675Y302742D01*
X274008Y302950D01*
X274217Y303200D01*
X274258Y303450D01*
X274175Y303742D01*
X273883Y303950D01*
X273592Y304033D01*
X273217D01*
G01X273592D02*
X273842Y304158D01*
X274050Y304367D01*
X274133Y304617D01*
X274050Y304867D01*
X273842Y305075D01*
X273467Y305200D01*
X273092Y305158D01*
X272717Y304992D01*
G01X275592Y302992D02*
X275883Y302783D01*
X276217Y302700D01*
X276550Y302783D01*
X276842Y303033D01*
X277050Y303408D01*
X277133Y303783D01*
Y304242D01*
X277050Y304617D01*
X276842Y304950D01*
X276592Y305117D01*
X276300Y305200D01*
X275967Y305117D01*
X275717Y304950D01*
X275550Y304700D01*
X275467Y304367D01*
X275550Y304075D01*
X275758Y303783D01*
X276008Y303617D01*
X276300Y303575D01*
X276633Y303658D01*
X276883Y303867D01*
X277133Y304242D01*
G01X284708Y159917D02*
X284583Y159667D01*
X284500Y159375D01*
Y159042D01*
X284625Y158667D01*
X284833Y158375D01*
X285083Y158167D01*
X285500Y158000D01*
X285875Y157958D01*
X286250Y158042D01*
X286500Y158167D01*
X286750Y158417D01*
X286917Y158708D01*
X287000Y159000D01*
Y159292D01*
X286917Y159583D01*
X286792Y159833D01*
X286625Y160042D01*
G01X287000Y162500D02*
X284500D01*
X286292Y160958D01*
Y163042D01*
G01X284917Y164208D02*
X284667Y164458D01*
X284542Y164750D01*
X284500Y165083D01*
X284583Y165500D01*
X284792Y165792D01*
X285042Y165875D01*
X285292Y165833D01*
X285500Y165667D01*
X285917Y164833D01*
X286208Y164458D01*
X286625Y164208D01*
X287000Y164125D01*
Y165875D01*
G01X285125Y324000D02*
Y326500D01*
G01X286875D02*
Y324000D01*
G01Y325250D02*
X285125D01*
G01X289000Y324000D02*
Y326500D01*
X288500Y326000D01*
G01Y324000D02*
X289500D01*
G01X303917Y121792D02*
X303667Y121917D01*
X303375Y122000D01*
X303042D01*
X302667Y121875D01*
X302375Y121667D01*
X302167Y121417D01*
X302000Y121000D01*
X301958Y120625D01*
X302042Y120250D01*
X302167Y120000D01*
X302417Y119750D01*
X302708Y119583D01*
X303000Y119500D01*
X303292D01*
X303583Y119583D01*
X303833Y119708D01*
X304042Y119875D01*
G01X306500Y119500D02*
Y122000D01*
X304958Y120208D01*
X307042D01*
G01X308083Y120000D02*
X308333Y119708D01*
X308667Y119542D01*
X309042Y119500D01*
X309375Y119542D01*
X309708Y119750D01*
X309917Y120000D01*
X309958Y120250D01*
X309875Y120542D01*
X309583Y120750D01*
X309292Y120833D01*
X308917D01*
G01X309292D02*
X309542Y120958D01*
X309750Y121167D01*
X309833Y121417D01*
X309750Y121667D01*
X309542Y121875D01*
X309167Y122000D01*
X308792Y121958D01*
X308417Y121792D01*
G01X300667Y132000D02*
Y134500D01*
X301708D01*
X302042Y134375D01*
X302250Y134208D01*
X302333Y133875D01*
X302250Y133542D01*
X302000Y133333D01*
X301708Y133208D01*
X300667D01*
G01X301708D02*
X302333Y132000D01*
G01X305000D02*
Y134500D01*
X303458Y132708D01*
X305542D01*
G01X307417Y132000D02*
X307500Y132542D01*
X307625Y133000D01*
X307792Y133417D01*
X308000Y133875D01*
X308333Y134500D01*
X306667D01*
G01X300667Y139500D02*
Y142000D01*
X301708D01*
X302042Y141875D01*
X302250Y141708D01*
X302333Y141375D01*
X302250Y141042D01*
X302000Y140833D01*
X301708Y140708D01*
X300667D01*
G01X301708D02*
X302333Y139500D01*
G01X305000D02*
Y142000D01*
X303458Y140208D01*
X305542D01*
G01X304000Y147667D02*
X301500D01*
Y148708D01*
X301625Y149042D01*
X301792Y149250D01*
X302125Y149333D01*
X302458Y149250D01*
X302667Y149000D01*
X302792Y148708D01*
Y147667D01*
G01Y148708D02*
X304000Y149333D01*
G01Y152000D02*
X301500D01*
X303292Y150458D01*
Y152542D01*
G01X304000Y155000D02*
X301500D01*
X303292Y153458D01*
Y155542D01*
G01X294583Y176500D02*
Y174708D01*
X294750Y174333D01*
X295083Y174083D01*
X295500Y174000D01*
X295917Y174083D01*
X296250Y174333D01*
X296417Y174708D01*
Y176500D01*
G01X297583Y174375D02*
X297833Y174167D01*
X298125Y174042D01*
X298500Y174000D01*
X298875Y174083D01*
X299167Y174250D01*
X299375Y174542D01*
X299417Y174875D01*
X299333Y175208D01*
X299125Y175417D01*
X298833Y175583D01*
X298542Y175625D01*
X298250Y175583D01*
X297875Y175417D01*
X298000Y176500D01*
X299125D01*
G01X301667Y251500D02*
Y254000D01*
X302708D01*
X303042Y253875D01*
X303250Y253708D01*
X303333Y253375D01*
X303250Y253042D01*
X303000Y252833D01*
X302708Y252708D01*
X301667D01*
G01X302708D02*
X303333Y251500D01*
G01X306000D02*
Y254000D01*
X304458Y252208D01*
X306542D01*
G01X307708Y252542D02*
X308000Y252833D01*
X308250Y253000D01*
X308583Y253083D01*
X308875Y253000D01*
X309083Y252833D01*
X309250Y252583D01*
X309292Y252292D01*
X309250Y252042D01*
X309083Y251792D01*
X308833Y251583D01*
X308542Y251500D01*
X308208Y251583D01*
X307917Y251833D01*
X307750Y252208D01*
X307708Y252625D01*
X307792Y253167D01*
X307917Y253458D01*
X308125Y253750D01*
X308417Y253958D01*
X308708Y254000D01*
X309000Y253917D01*
X309208Y253708D01*
G01X301667Y255500D02*
Y258000D01*
X302708D01*
X303042Y257875D01*
X303250Y257708D01*
X303333Y257375D01*
X303250Y257042D01*
X303000Y256833D01*
X302708Y256708D01*
X301667D01*
G01X302708D02*
X303333Y255500D01*
G01X304708Y257583D02*
X304958Y257833D01*
X305250Y257958D01*
X305583Y258000D01*
X306000Y257917D01*
X306292Y257708D01*
X306375Y257458D01*
X306333Y257208D01*
X306167Y257000D01*
X305333Y256583D01*
X304958Y256292D01*
X304708Y255875D01*
X304625Y255500D01*
X306375D01*
G01X299417Y321292D02*
X299167Y321417D01*
X298875Y321500D01*
X298542D01*
X298167Y321375D01*
X297875Y321167D01*
X297667Y320917D01*
X297500Y320500D01*
X297458Y320125D01*
X297542Y319750D01*
X297667Y319500D01*
X297917Y319250D01*
X298208Y319083D01*
X298500Y319000D01*
X298792D01*
X299083Y319083D01*
X299333Y319208D01*
X299542Y319375D01*
G01X300542Y319000D02*
Y321500D01*
X302458Y319000D01*
Y321500D01*
G01X304500Y319000D02*
Y321500D01*
X304000Y321000D01*
G01Y319000D02*
X305000D01*
G01X307500Y147667D02*
X305000D01*
Y148708D01*
X305125Y149042D01*
X305292Y149250D01*
X305625Y149333D01*
X305958Y149250D01*
X306167Y149000D01*
X306292Y148708D01*
Y147667D01*
G01Y148708D02*
X307500Y149333D01*
G01Y152000D02*
X305000D01*
X306792Y150458D01*
Y152542D01*
G01X307125Y153583D02*
X307333Y153833D01*
X307458Y154125D01*
X307500Y154500D01*
X307417Y154875D01*
X307250Y155167D01*
X306958Y155375D01*
X306625Y155417D01*
X306292Y155333D01*
X306083Y155125D01*
X305917Y154833D01*
X305875Y154542D01*
X305917Y154250D01*
X306083Y153875D01*
X305000Y154000D01*
Y155125D01*
G01X312667Y287375D02*
X312875Y287708D01*
X313000Y288083D01*
Y288417D01*
X312875Y288750D01*
X312667Y289000D01*
X312375Y289125D01*
X312083Y289042D01*
X311833Y288833D01*
X311667Y288458D01*
X311583Y287958D01*
X311417Y287667D01*
X311125Y287542D01*
X310833Y287625D01*
X310625Y287833D01*
X310500Y288125D01*
Y288417D01*
X310583Y288708D01*
X310792Y288958D01*
G01X313000Y290333D02*
X310500D01*
Y291167D01*
X310625Y291500D01*
X310792Y291750D01*
X311042Y291958D01*
X311333Y292125D01*
X311750Y292167D01*
X312167Y292125D01*
X312458Y291958D01*
X312708Y291750D01*
X312875Y291500D01*
X313000Y291167D01*
Y290333D01*
G01Y293208D02*
X310500Y294250D01*
X313000Y295292D01*
G01X312125Y294917D02*
Y293583D01*
G01X311750Y308500D02*
Y309333D01*
X312500D01*
X312750Y309083D01*
X312917Y308792D01*
X313000Y308375D01*
X312917Y307958D01*
X312750Y307667D01*
X312500Y307417D01*
X312208Y307250D01*
X311875Y307167D01*
X311583D01*
X311333Y307250D01*
X311042Y307417D01*
X310792Y307667D01*
X310625Y307917D01*
X310500Y308250D01*
Y308542D01*
X310583Y308875D01*
X310750Y309125D01*
G01X313000Y310292D02*
X310500D01*
X313000Y312208D01*
X310500D01*
G01X313000Y313333D02*
X310500D01*
Y314167D01*
X310625Y314500D01*
X310792Y314750D01*
X311042Y314958D01*
X311333Y315125D01*
X311750Y315167D01*
X312167Y315125D01*
X312458Y314958D01*
X312708Y314750D01*
X312875Y314500D01*
X313000Y314167D01*
Y313333D01*
G01X312667Y297875D02*
X312875Y298208D01*
X313000Y298583D01*
Y298917D01*
X312875Y299250D01*
X312667Y299500D01*
X312375Y299625D01*
X312083Y299542D01*
X311833Y299333D01*
X311667Y298958D01*
X311583Y298458D01*
X311417Y298167D01*
X311125Y298042D01*
X310833Y298125D01*
X310625Y298333D01*
X310500Y298625D01*
Y298917D01*
X310583Y299208D01*
X310792Y299458D01*
G01X310708Y302667D02*
X310583Y302417D01*
X310500Y302125D01*
Y301792D01*
X310625Y301417D01*
X310833Y301125D01*
X311083Y300917D01*
X311500Y300750D01*
X311875Y300708D01*
X312250Y300792D01*
X312500Y300917D01*
X312750Y301167D01*
X312917Y301458D01*
X313000Y301750D01*
Y302042D01*
X312917Y302333D01*
X312792Y302583D01*
X312625Y302792D01*
G01X310500Y303917D02*
X313000D01*
Y305583D01*
G54D19*
G01X-148956Y-251503D02*
Y-269003D01*
X-140222D01*
G01X-127089Y-257337D02*
Y-269003D01*
G01Y-252670D02*
X-127526Y-252378D01*
Y-251795D01*
X-127089Y-251503D01*
X-126652Y-251795D01*
Y-252378D01*
X-127089Y-252670D01*
G01X-112646Y-273378D02*
X-111117Y-274545D01*
X-109371Y-274836D01*
X-107843Y-274545D01*
X-106532Y-273087D01*
X-105659Y-271045D01*
Y-257337D01*
G01Y-259670D02*
X-106532Y-258503D01*
X-107843Y-257628D01*
X-109371Y-257337D01*
X-111117Y-257920D01*
X-112209Y-259086D01*
X-113083Y-261128D01*
X-113519Y-263170D01*
X-113301Y-264920D01*
X-112427Y-266962D01*
X-111117Y-268420D01*
X-109371Y-269003D01*
X-108061Y-268711D01*
X-106532Y-267545D01*
X-105659Y-266379D01*
G01X-95801Y-269003D02*
Y-251503D01*
G01Y-259961D02*
X-94709Y-258503D01*
X-93617Y-257628D01*
X-91871Y-257337D01*
X-90561Y-257628D01*
X-89032Y-258795D01*
X-88377Y-260545D01*
Y-269003D01*
G01X-74589Y-251503D02*
Y-269003D01*
G01X-77646Y-257337D02*
X-71532D01*
G01X-60801Y-269003D02*
Y-257337D01*
G01Y-260253D02*
X-59927Y-258795D01*
X-58617Y-257628D01*
X-56871Y-257337D01*
X-55343Y-257628D01*
X-54032Y-258795D01*
X-53377Y-260836D01*
Y-269003D01*
G01X-39589Y-257337D02*
Y-269003D01*
G01Y-252670D02*
X-40026Y-252378D01*
Y-251795D01*
X-39589Y-251503D01*
X-39152Y-251795D01*
Y-252378D01*
X-39589Y-252670D01*
G01X-25801Y-269003D02*
Y-257337D01*
G01Y-260253D02*
X-24927Y-258795D01*
X-23617Y-257628D01*
X-21871Y-257337D01*
X-20343Y-257628D01*
X-19032Y-258795D01*
X-18377Y-260836D01*
Y-269003D01*
G01X-7646Y-273378D02*
X-6117Y-274545D01*
X-4371Y-274836D01*
X-2843Y-274545D01*
X-1532Y-273087D01*
X-659Y-271045D01*
Y-257337D01*
G01Y-259670D02*
X-1532Y-258503D01*
X-2843Y-257628D01*
X-4371Y-257337D01*
X-6117Y-257920D01*
X-7209Y-259086D01*
X-8083Y-261128D01*
X-8519Y-263170D01*
X-8301Y-264920D01*
X-7427Y-266962D01*
X-6117Y-268420D01*
X-4371Y-269003D01*
X-3061Y-268711D01*
X-1532Y-267545D01*
X-659Y-266379D01*
G01X26044Y-269003D02*
Y-251503D01*
X31284D01*
X33031Y-252378D01*
X34341Y-254420D01*
X34778Y-256753D01*
X34341Y-259086D01*
X33249Y-260836D01*
X31284Y-261712D01*
X26044D01*
G01X42452Y-251503D02*
X47911Y-269003D01*
X53370Y-251503D01*
G01X65411D02*
Y-269003D01*
G01X60389Y-251503D02*
X70433D01*
G01X94734Y-269003D02*
Y-251503D01*
X100411Y-266086D01*
X106088Y-251503D01*
Y-269003D01*
G01X117911Y-269586D02*
X117474Y-269295D01*
Y-268711D01*
X117911Y-268420D01*
X118348Y-268711D01*
Y-269295D01*
X117911Y-269586D01*
G01X131263Y-254420D02*
X132573Y-252670D01*
X134101Y-251795D01*
X135848Y-251503D01*
X138031Y-252086D01*
X139559Y-253545D01*
X139996Y-255294D01*
X139778Y-257045D01*
X138904Y-258503D01*
X134538Y-261420D01*
X132573Y-263461D01*
X131263Y-266379D01*
X130826Y-269003D01*
X139996D01*
G01X164952D02*
X170411Y-251503D01*
X175870Y-269003D01*
G01X173904Y-262878D02*
X166917D01*
G01X191841Y-251503D02*
Y-269003D01*
G01Y-266379D02*
X190968Y-267837D01*
X189657Y-268711D01*
X188129Y-269003D01*
X186383Y-268420D01*
X185073Y-266962D01*
X184199Y-265212D01*
X183981Y-263170D01*
X184199Y-261128D01*
X185073Y-259378D01*
X186383Y-257920D01*
X188129Y-257337D01*
X189657Y-257628D01*
X190749Y-258212D01*
X191841Y-259378D01*
G01X209341Y-269003D02*
Y-257337D01*
G01Y-259378D02*
X208468Y-258212D01*
X207157Y-257628D01*
X205629Y-257337D01*
X204101Y-257920D01*
X202791Y-259086D01*
X201917Y-260836D01*
X201481Y-263170D01*
X201917Y-265503D01*
X202791Y-267253D01*
X204101Y-268420D01*
X205629Y-269003D01*
X207157Y-268711D01*
X208468Y-267837D01*
X209341Y-266670D01*
G01X218981Y-274836D02*
Y-257337D01*
G01Y-259961D02*
X220073Y-258503D01*
X221164Y-257628D01*
X222911Y-257337D01*
X224439Y-257628D01*
X225968Y-259086D01*
X226623Y-261128D01*
X226841Y-263170D01*
X226623Y-265212D01*
X225968Y-267253D01*
X224657Y-268420D01*
X222911Y-269003D01*
X221383Y-268711D01*
X219854Y-267837D01*
X218981Y-266670D01*
G01X240411Y-251503D02*
Y-269003D01*
G01X237354Y-257337D02*
X243468D01*
G01X257911Y-269003D02*
X256601Y-268711D01*
X255291Y-267545D01*
X254417Y-265503D01*
X253981Y-263170D01*
X254417Y-260836D01*
X255291Y-258795D01*
X256601Y-257628D01*
X257911Y-257337D01*
X259221Y-257628D01*
X260531Y-258795D01*
X261404Y-260836D01*
X261623Y-263170D01*
X261404Y-265503D01*
X260531Y-267545D01*
X259221Y-268711D01*
X257911Y-269003D01*
G01X272354D02*
Y-257337D01*
G01Y-259670D02*
X273446Y-258503D01*
X274538Y-257628D01*
X276066Y-257337D01*
X277157Y-257628D01*
X278468Y-258503D01*
G01X315214Y-252962D02*
X313904Y-252086D01*
X312376Y-251503D01*
X310629D01*
X308664Y-252378D01*
X307136Y-253836D01*
X306044Y-255587D01*
X305171Y-258503D01*
X304952Y-261128D01*
X305389Y-263753D01*
X306044Y-265503D01*
X307354Y-267253D01*
X308883Y-268420D01*
X310411Y-269003D01*
X311939D01*
X313468Y-268420D01*
X314778Y-267545D01*
X315870Y-266379D01*
G01X331841Y-269003D02*
Y-257337D01*
G01Y-259378D02*
X330968Y-258212D01*
X329657Y-257628D01*
X328129Y-257337D01*
X326601Y-257920D01*
X325291Y-259086D01*
X324417Y-260836D01*
X323981Y-263170D01*
X324417Y-265503D01*
X325291Y-267253D01*
X326601Y-268420D01*
X328129Y-269003D01*
X329657Y-268711D01*
X330968Y-267837D01*
X331841Y-266670D01*
G01X342354Y-269003D02*
Y-257337D01*
G01Y-259670D02*
X343446Y-258503D01*
X344538Y-257628D01*
X346066Y-257337D01*
X347157Y-257628D01*
X348468Y-258503D01*
G01X366841Y-251503D02*
Y-269003D01*
G01Y-266379D02*
X365968Y-267837D01*
X364657Y-268711D01*
X363129Y-269003D01*
X361383Y-268420D01*
X360073Y-266962D01*
X359199Y-265212D01*
X358981Y-263170D01*
X359199Y-261128D01*
X360073Y-259378D01*
X361383Y-257920D01*
X363129Y-257337D01*
X364657Y-257628D01*
X365749Y-258212D01*
X366841Y-259378D01*
G01X68484Y-224003D02*
Y-206503D01*
X74161Y-221086D01*
X79838Y-206503D01*
Y-224003D01*
G01X91661D02*
X90351Y-223711D01*
X89041Y-222545D01*
X88167Y-220503D01*
X87731Y-218170D01*
X88167Y-215836D01*
X89041Y-213795D01*
X90351Y-212628D01*
X91661Y-212337D01*
X92971Y-212628D01*
X94281Y-213795D01*
X95154Y-215836D01*
X95373Y-218170D01*
X95154Y-220503D01*
X94281Y-222545D01*
X92971Y-223711D01*
X91661Y-224003D01*
G01X113091Y-206503D02*
Y-224003D01*
G01Y-221379D02*
X112218Y-222837D01*
X110907Y-223711D01*
X109379Y-224003D01*
X107633Y-223420D01*
X106323Y-221962D01*
X105449Y-220212D01*
X105231Y-218170D01*
X105449Y-216128D01*
X106323Y-214378D01*
X107633Y-212920D01*
X109379Y-212337D01*
X110907Y-212628D01*
X111999Y-213212D01*
X113091Y-214378D01*
G01X123386Y-216128D02*
X130373D01*
X129718Y-214086D01*
X128626Y-212920D01*
X127098Y-212337D01*
X125569Y-212628D01*
X124259Y-213503D01*
X123386Y-215545D01*
X122949Y-217295D01*
Y-219045D01*
X123386Y-220795D01*
X124478Y-222545D01*
X125788Y-223711D01*
X127316Y-224003D01*
X128844Y-223420D01*
X130373Y-221670D01*
G01X144161Y-224003D02*
Y-206503D01*
G01X424761Y-269003D02*
Y-251503D01*
X422141Y-255003D01*
G01Y-269003D02*
X427381D01*
G01X437458Y-266379D02*
X438767Y-267837D01*
X440296Y-268711D01*
X442261Y-269003D01*
X444226Y-268420D01*
X445754Y-267253D01*
X446846Y-265212D01*
X447064Y-262878D01*
X446628Y-260545D01*
X445536Y-259086D01*
X444007Y-257920D01*
X442479Y-257628D01*
X440951Y-257920D01*
X438986Y-259086D01*
X439641Y-251503D01*
X445536D01*
G01X459324Y-269003D02*
X459761Y-265212D01*
X460416Y-262003D01*
X461289Y-259086D01*
X462381Y-255878D01*
X464128Y-251503D01*
X455394D01*
G01X472458Y-266379D02*
X473767Y-267837D01*
X475296Y-268711D01*
X477261Y-269003D01*
X479226Y-268420D01*
X480754Y-267253D01*
X481846Y-265212D01*
X482064Y-262878D01*
X481628Y-260545D01*
X480536Y-259086D01*
X479007Y-257920D01*
X477479Y-257628D01*
X475951Y-257920D01*
X473986Y-259086D01*
X474641Y-251503D01*
X480536D01*
G01X494761D02*
X493014Y-252086D01*
X491704Y-253545D01*
X490831Y-255294D01*
X490176Y-257628D01*
X489958Y-260253D01*
X490176Y-262878D01*
X490831Y-265212D01*
X491704Y-266962D01*
X493014Y-268420D01*
X494761Y-269003D01*
X496507Y-268420D01*
X497818Y-266962D01*
X498691Y-265212D01*
X499346Y-262878D01*
X499564Y-260253D01*
X499346Y-257628D01*
X498691Y-255294D01*
X497818Y-253545D01*
X496507Y-252086D01*
X494761Y-251503D01*
G01X411644Y-224003D02*
Y-206503D01*
X416884D01*
X418631Y-207378D01*
X419941Y-209420D01*
X420378Y-211753D01*
X419941Y-214086D01*
X418849Y-215836D01*
X416884Y-216712D01*
X411644D01*
G01X438314Y-207962D02*
X437004Y-207086D01*
X435476Y-206503D01*
X433729D01*
X431764Y-207378D01*
X430236Y-208836D01*
X429144Y-210587D01*
X428271Y-213503D01*
X428052Y-216128D01*
X428489Y-218753D01*
X429144Y-220503D01*
X430454Y-222253D01*
X431983Y-223420D01*
X433511Y-224003D01*
X435039D01*
X436568Y-223420D01*
X437878Y-222545D01*
X438970Y-221379D01*
G01X452757Y-214670D02*
X453631Y-213795D01*
X454286Y-212337D01*
X454723Y-210294D01*
X454286Y-208545D01*
X453413Y-207378D01*
X451884Y-206503D01*
X445989D01*
Y-224003D01*
X453194D01*
X454723Y-222837D01*
X455596Y-221086D01*
X456033Y-219045D01*
X455596Y-217003D01*
X454286Y-215253D01*
X452757Y-214670D01*
X445989D01*
G01X461961Y-229836D02*
X475061D01*
G01X480989Y-224003D02*
Y-206503D01*
X491033Y-224003D01*
Y-206503D01*
G01X503511Y-224003D02*
X501764Y-223711D01*
X500236Y-222545D01*
X498926Y-220795D01*
X498052Y-218753D01*
X497616Y-216420D01*
Y-214086D01*
X498052Y-211753D01*
X498926Y-209711D01*
X500236Y-207962D01*
X501764Y-206795D01*
X503511Y-206503D01*
X505257Y-206795D01*
X506786Y-207962D01*
X508096Y-209711D01*
X508970Y-211753D01*
X509406Y-214086D01*
Y-216420D01*
X508970Y-218753D01*
X508096Y-220795D01*
X506786Y-222545D01*
X505257Y-223711D01*
X503511Y-224003D01*
G01X554352Y-206503D02*
X559811Y-224003D01*
X565270Y-206503D01*
G01X581678Y-224003D02*
X572944D01*
Y-206503D01*
X581678D01*
G01X578184Y-214961D02*
X572944D01*
G01X590444Y-224003D02*
Y-206503D01*
X595903D01*
X597649Y-207378D01*
X598741Y-208545D01*
X599178Y-210878D01*
X598741Y-213212D01*
X597431Y-214670D01*
X595903Y-215545D01*
X590444D01*
G01X595903D02*
X599178Y-224003D01*
G01X612311Y-224586D02*
X611874Y-224295D01*
Y-223711D01*
X612311Y-223420D01*
X612748Y-223711D01*
Y-224295D01*
X612311Y-224586D01*
G01X586061Y-269003D02*
Y-251503D01*
X583441Y-255003D01*
G01Y-269003D02*
X588681D01*
G01X692261Y-251503D02*
Y-269003D01*
G01X687239Y-251503D02*
X697283D01*
G01X705176Y-266670D02*
X706923Y-268128D01*
X708888Y-269003D01*
X710634D01*
X712381Y-268128D01*
X713691Y-266670D01*
X714346Y-264628D01*
X713909Y-262587D01*
X712818Y-260836D01*
X710853Y-259670D01*
X708233Y-259086D01*
X706704Y-257920D01*
X706049Y-255878D01*
X706486Y-253836D01*
X707578Y-252378D01*
X709106Y-251503D01*
X710634D01*
X712163Y-252086D01*
X713473Y-253545D01*
G01X724641Y-251503D02*
X729881D01*
G01X727261D02*
Y-269003D01*
G01X724641D02*
X729881D01*
G01X740394Y-251503D02*
Y-269003D01*
X749128D01*
G01X757458D02*
Y-251503D01*
G01X765754D02*
X757458Y-262295D01*
G01X767064Y-269003D02*
X761169Y-257337D01*
G01X687894Y-206503D02*
Y-224003D01*
X696628D01*
G01X713691D02*
Y-212337D01*
G01Y-214378D02*
X712818Y-213212D01*
X711507Y-212628D01*
X709979Y-212337D01*
X708451Y-212920D01*
X707141Y-214086D01*
X706267Y-215836D01*
X705831Y-218170D01*
X706267Y-220503D01*
X707141Y-222253D01*
X708451Y-223420D01*
X709979Y-224003D01*
X711507Y-223711D01*
X712818Y-222837D01*
X713691Y-221670D01*
G01X722676Y-229253D02*
X723986Y-229836D01*
X725733Y-229253D01*
X726824Y-228087D01*
X727698Y-226628D01*
X729007Y-221962D01*
X731846Y-212337D01*
G01X724859D02*
X729007Y-221962D01*
G01X741486Y-216128D02*
X748473D01*
X747818Y-214086D01*
X746726Y-212920D01*
X745198Y-212337D01*
X743669Y-212628D01*
X742359Y-213503D01*
X741486Y-215545D01*
X741049Y-217295D01*
Y-219045D01*
X741486Y-220795D01*
X742578Y-222545D01*
X743888Y-223711D01*
X745416Y-224003D01*
X746944Y-223420D01*
X748473Y-221670D01*
G01X759204Y-224003D02*
Y-212337D01*
G01Y-214670D02*
X760296Y-213503D01*
X761388Y-212628D01*
X762916Y-212337D01*
X764007Y-212628D01*
X765318Y-213503D01*
G01X830008Y-224003D02*
Y-206503D01*
X834374D01*
X836121Y-207378D01*
X837431Y-208545D01*
X838523Y-210294D01*
X839396Y-212337D01*
X839614Y-215253D01*
X839396Y-218170D01*
X838523Y-220212D01*
X837431Y-221962D01*
X836121Y-223128D01*
X834374Y-224003D01*
X830008D01*
G01X849036Y-216128D02*
X856023D01*
X855368Y-214086D01*
X854276Y-212920D01*
X852748Y-212337D01*
X851219Y-212628D01*
X849909Y-213503D01*
X849036Y-215545D01*
X848599Y-217295D01*
Y-219045D01*
X849036Y-220795D01*
X850128Y-222545D01*
X851438Y-223711D01*
X852966Y-224003D01*
X854494Y-223420D01*
X856023Y-221670D01*
G01X866536Y-221962D02*
X867628Y-223128D01*
X869156Y-224003D01*
X870466D01*
X871776Y-223420D01*
X872649Y-222545D01*
X873086Y-221379D01*
X872868Y-219628D01*
X871994Y-218753D01*
X868064Y-217003D01*
X867191Y-214961D01*
X867628Y-213503D01*
X868501Y-212628D01*
X869811Y-212337D01*
X871121Y-212628D01*
X872431Y-213503D01*
G01X887311Y-212337D02*
Y-224003D01*
G01Y-207670D02*
X886874Y-207378D01*
Y-206795D01*
X887311Y-206503D01*
X887748Y-206795D01*
Y-207378D01*
X887311Y-207670D01*
G01X901754Y-228378D02*
X903283Y-229545D01*
X905029Y-229836D01*
X906557Y-229545D01*
X907868Y-228087D01*
X908741Y-226045D01*
Y-212337D01*
G01Y-214670D02*
X907868Y-213503D01*
X906557Y-212628D01*
X905029Y-212337D01*
X903283Y-212920D01*
X902191Y-214086D01*
X901317Y-216128D01*
X900881Y-218170D01*
X901099Y-219920D01*
X901973Y-221962D01*
X903283Y-223420D01*
X905029Y-224003D01*
X906339Y-223711D01*
X907868Y-222545D01*
X908741Y-221379D01*
G01X918599Y-224003D02*
Y-212337D01*
G01Y-215253D02*
X919473Y-213795D01*
X920783Y-212628D01*
X922529Y-212337D01*
X924057Y-212628D01*
X925368Y-213795D01*
X926023Y-215836D01*
Y-224003D01*
G01X936536Y-216128D02*
X943523D01*
X942868Y-214086D01*
X941776Y-212920D01*
X940248Y-212337D01*
X938719Y-212628D01*
X937409Y-213503D01*
X936536Y-215545D01*
X936099Y-217295D01*
Y-219045D01*
X936536Y-220795D01*
X937628Y-222545D01*
X938938Y-223711D01*
X940466Y-224003D01*
X941994Y-223420D01*
X943523Y-221670D01*
G01X954254Y-224003D02*
Y-212337D01*
G01Y-214670D02*
X955346Y-213503D01*
X956438Y-212628D01*
X957966Y-212337D01*
X959057Y-212628D01*
X960368Y-213503D01*
G01X874194Y-265503D02*
X875286Y-267253D01*
X876596Y-268420D01*
X878124Y-269003D01*
X879871Y-268420D01*
X881181Y-267253D01*
X882491Y-265503D01*
X882928Y-263170D01*
Y-251503D01*
G01X896061Y-269003D02*
X894314Y-268711D01*
X892786Y-267545D01*
X891476Y-265795D01*
X890602Y-263753D01*
X890166Y-261420D01*
Y-259086D01*
X890602Y-256753D01*
X891476Y-254711D01*
X892786Y-252962D01*
X894314Y-251795D01*
X896061Y-251503D01*
X897807Y-251795D01*
X899336Y-252962D01*
X900646Y-254711D01*
X901520Y-256753D01*
X901956Y-259086D01*
Y-261420D01*
X901520Y-263753D01*
X900646Y-265795D01*
X899336Y-267545D01*
X897807Y-268711D01*
X896061Y-269003D01*
G01X913561D02*
Y-261128D01*
X909194Y-251503D01*
G01X917928D02*
X913561Y-261128D01*
G01X1001011Y-269003D02*
Y-251503D01*
X998391Y-255003D01*
G01Y-269003D02*
X1003631D01*
G01X1014363Y-254420D02*
X1015673Y-252670D01*
X1017201Y-251795D01*
X1018948Y-251503D01*
X1021131Y-252086D01*
X1022659Y-253545D01*
X1023096Y-255294D01*
X1022878Y-257045D01*
X1022004Y-258503D01*
X1017638Y-261420D01*
X1015673Y-263461D01*
X1014363Y-266379D01*
X1013926Y-269003D01*
X1023096D01*
G01X1032081Y-269586D02*
X1039941Y-251503D01*
G01X1048708Y-265503D02*
X1050017Y-267545D01*
X1051764Y-268711D01*
X1053729Y-269003D01*
X1055476Y-268711D01*
X1057223Y-267253D01*
X1058314Y-265503D01*
X1058533Y-263753D01*
X1058096Y-261712D01*
X1056568Y-260253D01*
X1055039Y-259670D01*
X1053074D01*
G01X1055039D02*
X1056349Y-258795D01*
X1057441Y-257337D01*
X1057878Y-255587D01*
X1057441Y-253836D01*
X1056349Y-252378D01*
X1054384Y-251503D01*
X1052419Y-251795D01*
X1050454Y-252962D01*
G01X1071011Y-251503D02*
X1069264Y-252086D01*
X1067954Y-253545D01*
X1067081Y-255294D01*
X1066426Y-257628D01*
X1066208Y-260253D01*
X1066426Y-262878D01*
X1067081Y-265212D01*
X1067954Y-266962D01*
X1069264Y-268420D01*
X1071011Y-269003D01*
X1072757Y-268420D01*
X1074068Y-266962D01*
X1074941Y-265212D01*
X1075596Y-262878D01*
X1075814Y-260253D01*
X1075596Y-257628D01*
X1074941Y-255294D01*
X1074068Y-253545D01*
X1072757Y-252086D01*
X1071011Y-251503D01*
G01X1084581Y-269586D02*
X1092441Y-251503D01*
G01X1101863Y-254420D02*
X1103173Y-252670D01*
X1104701Y-251795D01*
X1106448Y-251503D01*
X1108631Y-252086D01*
X1110159Y-253545D01*
X1110596Y-255294D01*
X1110378Y-257045D01*
X1109504Y-258503D01*
X1105138Y-261420D01*
X1103173Y-263461D01*
X1101863Y-266379D01*
X1101426Y-269003D01*
X1110596D01*
G01X1123511Y-251503D02*
X1121764Y-252086D01*
X1120454Y-253545D01*
X1119581Y-255294D01*
X1118926Y-257628D01*
X1118708Y-260253D01*
X1118926Y-262878D01*
X1119581Y-265212D01*
X1120454Y-266962D01*
X1121764Y-268420D01*
X1123511Y-269003D01*
X1125257Y-268420D01*
X1126568Y-266962D01*
X1127441Y-265212D01*
X1128096Y-262878D01*
X1128314Y-260253D01*
X1128096Y-257628D01*
X1127441Y-255294D01*
X1126568Y-253545D01*
X1125257Y-252086D01*
X1123511Y-251503D01*
G01X1141011Y-269003D02*
Y-251503D01*
X1138391Y-255003D01*
G01Y-269003D02*
X1143631D01*
G01X1154363Y-261712D02*
X1155891Y-259670D01*
X1157201Y-258503D01*
X1158948Y-257920D01*
X1160476Y-258503D01*
X1161568Y-259670D01*
X1162441Y-261420D01*
X1162659Y-263461D01*
X1162441Y-265212D01*
X1161568Y-266962D01*
X1160257Y-268420D01*
X1158729Y-269003D01*
X1156983Y-268420D01*
X1155454Y-266670D01*
X1154581Y-264045D01*
X1154363Y-261128D01*
X1154799Y-257337D01*
X1155454Y-255294D01*
X1156546Y-253253D01*
X1158074Y-251795D01*
X1159603Y-251503D01*
X1161131Y-252086D01*
X1162223Y-253545D01*
G01X1048708Y-224003D02*
Y-206503D01*
X1053074D01*
X1054821Y-207378D01*
X1056131Y-208545D01*
X1057223Y-210294D01*
X1058096Y-212337D01*
X1058314Y-215253D01*
X1058096Y-218170D01*
X1057223Y-220212D01*
X1056131Y-221962D01*
X1054821Y-223128D01*
X1053074Y-224003D01*
X1048708D01*
G01X1074941D02*
Y-212337D01*
G01Y-214378D02*
X1074068Y-213212D01*
X1072757Y-212628D01*
X1071229Y-212337D01*
X1069701Y-212920D01*
X1068391Y-214086D01*
X1067517Y-215836D01*
X1067081Y-218170D01*
X1067517Y-220503D01*
X1068391Y-222253D01*
X1069701Y-223420D01*
X1071229Y-224003D01*
X1072757Y-223711D01*
X1074068Y-222837D01*
X1074941Y-221670D01*
G01X1088511Y-206503D02*
Y-224003D01*
G01X1085454Y-212337D02*
X1091568D01*
G01X1102736Y-216128D02*
X1109723D01*
X1109068Y-214086D01*
X1107976Y-212920D01*
X1106448Y-212337D01*
X1104919Y-212628D01*
X1103609Y-213503D01*
X1102736Y-215545D01*
X1102299Y-217295D01*
Y-219045D01*
X1102736Y-220795D01*
X1103828Y-222545D01*
X1105138Y-223711D01*
X1106666Y-224003D01*
X1108194Y-223420D01*
X1109723Y-221670D01*
G01X7100Y296400D02*
Y268600D01*
X34900D01*
Y296400D01*
X7100D01*
G01X68700Y292189D02*
Y296189D01*
X61300D01*
G01X62100Y308789D02*
Y305789D01*
X65100D01*
G01X72700Y296689D02*
Y300689D01*
X65300D01*
G01X67600Y326689D02*
Y324689D01*
G01X65100Y325589D02*
X62100D01*
Y322589D01*
G01X64000Y342889D02*
X60000D01*
Y335489D01*
G01X76200Y343000D02*
Y347000D01*
X68800D01*
G01X75400Y306689D02*
Y303689D01*
G01X77900Y305789D02*
X80900D01*
Y308789D01*
G01X117949Y217442D02*
Y209642D01*
X105349D01*
Y217442D01*
X117949D01*
G01X97000Y286200D02*
X93000D01*
Y278800D01*
G01X101000Y286200D02*
X97000D01*
Y278800D01*
G01X106950Y307100D02*
Y289900D01*
X97050D01*
Y307100D01*
X106950D01*
G01Y297100D02*
X106800D01*
X105550Y298350D01*
X106750Y299550D01*
X107000D01*
G01X94800Y319000D02*
Y315000D01*
X102200D01*
G01Y323000D02*
Y327000D01*
X94800D01*
G01Y323000D02*
Y319000D01*
X102200D01*
G01X114449Y211042D02*
X115049Y211142D01*
X115549Y211642D01*
X115949Y212142D01*
X116149Y212742D01*
X116249Y213542D01*
X116149Y214242D01*
X115949Y214942D01*
X115549Y215442D01*
X115049Y215842D01*
X114449Y216042D01*
X113749Y215842D01*
X113249Y215442D01*
X112949Y214942D01*
X112649Y214242D01*
X112549Y213542D01*
X112649Y212742D01*
X112949Y212142D01*
X113249Y211642D01*
X113749Y211142D01*
X114449Y211042D01*
G01X108849Y216042D02*
Y211042D01*
X109849Y212042D01*
G01Y216042D02*
X107849D01*
G01X116500Y287200D02*
X112500D01*
Y279800D01*
G01X121000Y285700D02*
X117000D01*
Y278300D01*
G01X109900Y299950D02*
X127100D01*
Y290050D01*
X109900D01*
Y299950D01*
G01X121000Y313700D02*
X117000D01*
Y306300D01*
G01Y313700D02*
X113000D01*
Y306300D01*
G01X125500Y313700D02*
X121500D01*
Y306300D01*
G01X119900Y299950D02*
Y299800D01*
X118650Y298550D01*
X117450Y299750D01*
Y300000D01*
G01X129500Y313700D02*
X125500D01*
Y306300D01*
G01X135400Y322700D02*
Y309300D01*
G01D02*
X142600D01*
G01Y322700D02*
X135400D01*
G01X142600Y309300D02*
Y322700D01*
G01X170311Y303700D02*
X166311D01*
Y296300D01*
G01X172968Y312594D02*
X169968D01*
G01X172968Y322437D02*
X170968D01*
G01X171961Y309500D02*
Y304500D01*
X176961D01*
G01X174311Y296300D02*
X178311D01*
Y303700D01*
G01X186000Y346700D02*
Y338900D01*
G01Y333300D02*
X193000D01*
G01X186000Y339700D02*
Y333300D01*
G01X176961Y332500D02*
X171961D01*
Y327500D01*
G01X193000Y346700D02*
X186000D01*
G01X200850Y308450D02*
Y339550D01*
X238150D01*
Y308450D01*
X200850D01*
G01X197511Y297500D02*
Y301500D01*
X190111D01*
G01X201811Y301700D02*
X197811D01*
Y294300D01*
G01X209511Y302000D02*
Y306000D01*
X202111D01*
G01X198654Y326374D02*
X201654D01*
G01X198654Y316531D02*
X200654D01*
G01X193000Y346700D02*
Y341500D01*
G01Y333300D02*
Y342000D01*
G01X199661Y327500D02*
Y332500D01*
X194661D01*
G01X226000Y35833D02*
X221000D01*
Y37917D01*
X221250Y38583D01*
X221583Y39000D01*
X222250Y39167D01*
X222917Y39000D01*
X223333Y38500D01*
X223583Y37917D01*
Y35833D01*
G01Y37917D02*
X226000Y39167D01*
G01Y43100D02*
X225917Y42433D01*
X225583Y41850D01*
X225083Y41350D01*
X224500Y41017D01*
X223833Y40850D01*
X223167D01*
X222500Y41017D01*
X221917Y41350D01*
X221417Y41850D01*
X221083Y42433D01*
X221000Y43100D01*
X221083Y43767D01*
X221417Y44350D01*
X221917Y44850D01*
X222500Y45183D01*
X223167Y45350D01*
X223833D01*
X224500Y45183D01*
X225083Y44850D01*
X225583Y44350D01*
X225917Y43767D01*
X226000Y43100D01*
G01Y46950D02*
X221000D01*
G01Y50450D02*
X226000D01*
G01X223500D02*
Y46950D01*
G01X225333Y52550D02*
X225750Y53217D01*
X226000Y53967D01*
Y54633D01*
X225750Y55300D01*
X225333Y55800D01*
X224750Y56050D01*
X224167Y55883D01*
X223667Y55467D01*
X223333Y54717D01*
X223167Y53717D01*
X222833Y53133D01*
X222250Y52883D01*
X221667Y53050D01*
X221250Y53467D01*
X221000Y54050D01*
Y54633D01*
X221167Y55217D01*
X221583Y55717D01*
G01X223083Y66833D02*
X222750Y66250D01*
X222667Y65750D01*
X222833Y65083D01*
X223167Y64583D01*
X223750Y64250D01*
X224333Y64167D01*
X224917Y64250D01*
X225417Y64583D01*
X225833Y65083D01*
X226000Y65750D01*
X225833Y66333D01*
X225500Y66833D01*
G01X226000Y71100D02*
X225917Y70600D01*
X225583Y70100D01*
X225000Y69767D01*
X224333Y69600D01*
X223667Y69767D01*
X223083Y70100D01*
X222750Y70600D01*
X222667Y71100D01*
X222750Y71600D01*
X223083Y72100D01*
X223667Y72433D01*
X224333Y72517D01*
X225000Y72433D01*
X225583Y72100D01*
X225917Y71600D01*
X226000Y71100D01*
G01Y74200D02*
X222667D01*
G01X223583D02*
X223167Y74450D01*
X222833Y74867D01*
X222667Y75450D01*
X222833Y76033D01*
X223167Y76450D01*
X223583Y76700D01*
X226000D01*
G01X223583D02*
X223167Y76950D01*
X222833Y77367D01*
X222667Y77950D01*
X222833Y78533D01*
X223167Y78950D01*
X223667Y79200D01*
X226000D01*
G01X227667Y80800D02*
X222667D01*
G01X223417D02*
X223000Y81217D01*
X222750Y81633D01*
X222667Y82300D01*
X222750Y82883D01*
X223167Y83467D01*
X223750Y83717D01*
X224333Y83800D01*
X224917Y83717D01*
X225500Y83467D01*
X225833Y82967D01*
X226000Y82300D01*
X225917Y81717D01*
X225667Y81133D01*
X225333Y80800D01*
G01X226000Y87900D02*
X221000D01*
G01X222667Y93500D02*
X226000D01*
G01X221333D02*
X221250Y93333D01*
X221083D01*
X221000Y93500D01*
X221083Y93667D01*
X221250D01*
X221333Y93500D01*
G01X226000Y100600D02*
X222667D01*
G01X223250D02*
X222917Y100267D01*
X222750Y99767D01*
X222667Y99183D01*
X222833Y98600D01*
X223167Y98100D01*
X223667Y97767D01*
X224333Y97600D01*
X225000Y97767D01*
X225500Y98100D01*
X225833Y98600D01*
X226000Y99183D01*
X225917Y99767D01*
X225667Y100267D01*
X225333Y100600D01*
G01X226000Y103283D02*
X222667D01*
G01X223500D02*
X223083Y103617D01*
X222750Y104117D01*
X222667Y104783D01*
X222750Y105367D01*
X223083Y105867D01*
X223667Y106117D01*
X226000D01*
G01X223083Y111633D02*
X222750Y111050D01*
X222667Y110550D01*
X222833Y109883D01*
X223167Y109383D01*
X223750Y109050D01*
X224333Y108967D01*
X224917Y109050D01*
X225417Y109383D01*
X225833Y109883D01*
X226000Y110550D01*
X225833Y111133D01*
X225500Y111633D01*
G01X223750Y114650D02*
Y117317D01*
X223167Y117067D01*
X222833Y116650D01*
X222667Y116067D01*
X222750Y115483D01*
X223000Y114983D01*
X223583Y114650D01*
X224083Y114483D01*
X224583D01*
X225083Y114650D01*
X225583Y115067D01*
X225917Y115567D01*
X226000Y116150D01*
X225833Y116733D01*
X225333Y117317D01*
G01X231458Y40629D02*
Y48429D01*
X244058D01*
Y40629D01*
X231458D01*
G01X234958Y47029D02*
X234358Y46929D01*
X233858Y46429D01*
X233458Y45929D01*
X233258Y45329D01*
X233158Y44529D01*
X233258Y43829D01*
X233458Y43129D01*
X233858Y42629D01*
X234358Y42229D01*
X234958Y42029D01*
X235658Y42229D01*
X236158Y42629D01*
X236458Y43129D01*
X236758Y43829D01*
X236858Y44529D01*
X236758Y45329D01*
X236458Y45929D01*
X236158Y46429D01*
X235658Y46929D01*
X234958Y47029D01*
G01X242500Y162750D02*
X234500D01*
Y150800D01*
X242500D01*
Y162750D01*
G01X236350Y150800D02*
X238350Y152800D01*
X240350Y150800D01*
G01X251000Y49333D02*
X252333Y48500D01*
X253833Y48000D01*
X255167D01*
X256500Y48500D01*
X257500Y49333D01*
X258000Y50500D01*
X257667Y51666D01*
X256833Y52667D01*
X255333Y53333D01*
X253333Y53667D01*
X252167Y54333D01*
X251667Y55500D01*
X252000Y56667D01*
X252833Y57500D01*
X254000Y58000D01*
X255167D01*
X256333Y57667D01*
X257333Y56833D01*
G01X261600Y49333D02*
X262933Y48500D01*
X264433Y48000D01*
X265767D01*
X267100Y48500D01*
X268100Y49333D01*
X268600Y50500D01*
X268267Y51666D01*
X267433Y52667D01*
X265933Y53333D01*
X263933Y53667D01*
X262767Y54333D01*
X262267Y55500D01*
X262600Y56667D01*
X263433Y57500D01*
X264600Y58000D01*
X265767D01*
X266933Y57667D01*
X267933Y56833D01*
G01X272033Y48000D02*
Y58000D01*
X275367D01*
X276700Y57500D01*
X277700Y56833D01*
X278533Y55833D01*
X279200Y54666D01*
X279367Y53000D01*
X279200Y51333D01*
X278533Y50167D01*
X277700Y49166D01*
X276700Y48500D01*
X275367Y48000D01*
X272033D01*
G01X286300D02*
Y58000D01*
X284300Y56000D01*
G01Y48000D02*
X288300D01*
G01X238758Y43029D02*
X239258Y42429D01*
X239958Y42129D01*
X240658Y42029D01*
X241358Y42129D01*
X241958Y42529D01*
X242458Y43029D01*
Y43529D01*
X242358Y44129D01*
X241758Y44529D01*
X241158Y44729D01*
X240458D01*
G01X241158D02*
X241658Y44929D01*
X242058Y45429D01*
X242258Y45929D01*
X242058Y46429D01*
X241658Y46829D01*
X240958Y47029D01*
X240158Y46929D01*
X239458Y46629D01*
G01X252551Y148394D02*
X290351D01*
Y59794D01*
X252551D01*
Y148394D01*
G01Y257056D02*
X290351D01*
Y168456D01*
X252551D01*
Y257056D01*
G01X253000Y260333D02*
X254333Y259500D01*
X255833Y259000D01*
X257167D01*
X258500Y259500D01*
X259500Y260333D01*
X260000Y261500D01*
X259667Y262666D01*
X258833Y263667D01*
X257333Y264333D01*
X255333Y264667D01*
X254167Y265333D01*
X253667Y266500D01*
X254000Y267667D01*
X254833Y268500D01*
X256000Y269000D01*
X257167D01*
X258333Y268667D01*
X259333Y267833D01*
G01X263600Y260333D02*
X264933Y259500D01*
X266433Y259000D01*
X267767D01*
X269100Y259500D01*
X270100Y260333D01*
X270600Y261500D01*
X270267Y262666D01*
X269433Y263667D01*
X267933Y264333D01*
X265933Y264667D01*
X264767Y265333D01*
X264267Y266500D01*
X264600Y267667D01*
X265433Y268500D01*
X266600Y269000D01*
X267767D01*
X268933Y268667D01*
X269933Y267833D01*
G01X274033Y259000D02*
Y269000D01*
X277367D01*
X278700Y268500D01*
X279700Y267833D01*
X280533Y266833D01*
X281200Y265666D01*
X281367Y264000D01*
X281200Y262333D01*
X280533Y261167D01*
X279700Y260166D01*
X278700Y259500D01*
X277367Y259000D01*
X274033D01*
G01X288300Y269000D02*
X286966Y268667D01*
X285967Y267833D01*
X285300Y266833D01*
X284800Y265500D01*
X284633Y264000D01*
X284800Y262500D01*
X285300Y261167D01*
X285967Y260166D01*
X286966Y259333D01*
X288300Y259000D01*
X289633Y259333D01*
X290633Y260166D01*
X291300Y261167D01*
X291800Y262500D01*
X291967Y264000D01*
X291800Y265500D01*
X291300Y266833D01*
X290633Y267833D01*
X289633Y268667D01*
X288300Y269000D01*
G01X240000Y308300D02*
X258000D01*
G01X240000Y319500D02*
Y308300D01*
G01Y335500D02*
Y346700D01*
G01D02*
X258000D01*
G01X258585Y13280D02*
X260835D01*
G01X258585Y7400D02*
Y13280D01*
G01X260835Y7400D02*
X258585D01*
G01X259935Y10435D02*
X258585D01*
G01X264335Y9070D02*
Y13280D01*
G01X264105Y8185D02*
X264335Y9070D01*
G01X263655Y7600D02*
X264105Y8185D01*
G01X263090Y7400D02*
X263655Y7600D01*
G01X262525D02*
X263090Y7400D01*
G01X262075Y8185D02*
X262525Y7600D01*
G01X261850Y9070D02*
X262075Y8185D01*
G01X261850Y13280D02*
Y9070D01*
G01X270300Y7495D02*
X269855Y7400D01*
G01X270700Y7890D02*
X270300Y7495D01*
G01X271035Y8480D02*
X270700Y7890D01*
G01Y12790D02*
X271035Y12200D01*
G01X270300Y13185D02*
X270700Y12790D01*
G01X269855Y13280D02*
X270300Y13185D01*
G01X269405D02*
X269855Y13280D01*
G01X269005Y12790D02*
X269405Y13185D01*
G01X268670Y12200D02*
X269005Y12790D01*
G01X268440Y11515D02*
X268670Y12200D01*
G01X268330Y10730D02*
X268440Y11515D01*
G01X268330Y9950D02*
Y10730D01*
G01X268440Y9165D02*
X268330Y9950D01*
G01X268670Y8480D02*
X268440Y9165D01*
G01X269005Y7890D02*
X268670Y8480D01*
G01X269405Y7495D02*
X269005Y7890D01*
G01X269855Y7400D02*
X269405Y7495D01*
G01X258000Y308300D02*
Y319500D01*
G01Y346700D02*
Y335500D01*
G01X271265Y9165D02*
X271035Y8480D01*
G01X271375Y9950D02*
X271265Y9165D01*
G01X271375Y10730D02*
Y9950D01*
G01X271265Y11515D02*
X271375Y10730D01*
G01X271035Y12200D02*
X271265Y11515D01*
G01X272280Y7400D02*
Y11320D01*
G01X274190Y10140D02*
Y7400D01*
G01X274020Y10830D02*
X274190Y10140D01*
G01X273680Y11220D02*
X274020Y10830D01*
G01X273290Y11320D02*
X273680Y11220D01*
G01X272835D02*
X273290Y11320D01*
G01X272500Y10830D02*
X272835Y11220D01*
G01X272280Y10340D02*
X272500Y10830D01*
G01X276615Y7400D02*
Y13280D01*
G01X280445Y8085D02*
X281180Y11320D01*
G01X280105Y6520D02*
X280445Y8085D01*
G01X279885Y6025D02*
X280105Y6520D01*
G01X279600Y5635D02*
X279885Y6025D01*
G01X279150Y5440D02*
X279600Y5635D01*
G01X278810D02*
X279150Y5440D01*
G01X279380Y11320D02*
X280445Y8085D01*
G01X273194Y377869D02*
Y381869D01*
X272394Y381069D01*
G01Y377869D02*
X273994D01*
G01X296833Y50710D02*
X297250Y51377D01*
X297500Y52127D01*
Y52793D01*
X297250Y53460D01*
X296833Y53960D01*
X296250Y54210D01*
X295667Y54043D01*
X295167Y53627D01*
X294833Y52877D01*
X294667Y51877D01*
X294333Y51293D01*
X293750Y51043D01*
X293167Y51210D01*
X292750Y51627D01*
X292500Y52210D01*
Y52793D01*
X292667Y53377D01*
X293083Y53877D01*
G01X296833Y56310D02*
X297250Y56977D01*
X297500Y57727D01*
Y58393D01*
X297250Y59060D01*
X296833Y59560D01*
X296250Y59810D01*
X295667Y59643D01*
X295167Y59227D01*
X294833Y58477D01*
X294667Y57477D01*
X294333Y56893D01*
X293750Y56643D01*
X293167Y56810D01*
X292750Y57227D01*
X292500Y57810D01*
Y58393D01*
X292667Y58977D01*
X293083Y59477D01*
G01X297500Y61827D02*
X292500D01*
Y63493D01*
X292750Y64160D01*
X293083Y64660D01*
X293583Y65077D01*
X294167Y65410D01*
X295000Y65493D01*
X295833Y65410D01*
X296417Y65077D01*
X296917Y64660D01*
X297250Y64160D01*
X297500Y63493D01*
Y61827D01*
G01X299167Y66760D02*
Y71760D01*
G01X294833Y75527D02*
X294583Y75860D01*
X294167Y76110D01*
X293583Y76277D01*
X293083Y76110D01*
X292750Y75777D01*
X292500Y75193D01*
Y72943D01*
X297500D01*
Y75693D01*
X297167Y76277D01*
X296667Y76610D01*
X296083Y76777D01*
X295500Y76610D01*
X295000Y76110D01*
X294833Y75527D01*
Y72943D01*
G01X297500Y80460D02*
X292500D01*
X293500Y79460D01*
G01X297500D02*
Y81460D01*
G01X298000Y137700D02*
X294000D01*
Y130300D01*
G01X298000Y145200D02*
X294000D01*
Y137800D01*
G01X292000Y148800D02*
X296000D01*
Y156200D01*
G01Y148800D02*
X300000D01*
Y156200D01*
G01X303000Y172200D02*
Y158800D01*
G01X293000D02*
Y172200D01*
G01X303000Y158800D02*
X293000D01*
G01Y172200D02*
X303000D01*
G01X306833Y219750D02*
X307250Y220417D01*
X307500Y221167D01*
Y221833D01*
X307250Y222500D01*
X306833Y223000D01*
X306250Y223250D01*
X305667Y223083D01*
X305167Y222667D01*
X304833Y221917D01*
X304667Y220917D01*
X304333Y220333D01*
X303750Y220083D01*
X303167Y220250D01*
X302750Y220667D01*
X302500Y221250D01*
Y221833D01*
X302667Y222417D01*
X303083Y222917D01*
G01X306833Y225350D02*
X307250Y226017D01*
X307500Y226767D01*
Y227433D01*
X307250Y228100D01*
X306833Y228600D01*
X306250Y228850D01*
X305667Y228683D01*
X305167Y228267D01*
X304833Y227517D01*
X304667Y226517D01*
X304333Y225933D01*
X303750Y225683D01*
X303167Y225850D01*
X302750Y226267D01*
X302500Y226850D01*
Y227433D01*
X302667Y228017D01*
X303083Y228517D01*
G01X307500Y230867D02*
X302500D01*
Y232533D01*
X302750Y233200D01*
X303083Y233700D01*
X303583Y234117D01*
X304167Y234450D01*
X305000Y234533D01*
X305833Y234450D01*
X306417Y234117D01*
X306917Y233700D01*
X307250Y233200D01*
X307500Y232533D01*
Y230867D01*
G01X309167Y235800D02*
Y240800D01*
G01X307500Y241817D02*
X302500Y243900D01*
X307500Y245983D01*
G01X305750Y245233D02*
Y242567D01*
G01X307500Y249500D02*
X302500D01*
X303500Y248500D01*
G01X307500D02*
Y250500D01*
G01X300200Y243000D02*
Y247000D01*
X292800D01*
G01Y251000D02*
Y247000D01*
X300200D01*
G01X296000Y316150D02*
X308000D01*
Y284850D01*
X296000D01*
Y316150D01*
G01X303422Y381202D02*
X303822Y381602D01*
X304289Y381802D01*
X304822Y381869D01*
X305489Y381736D01*
X305956Y381402D01*
X306089Y381002D01*
X306022Y380602D01*
X305756Y380269D01*
X304422Y379602D01*
X303822Y379136D01*
X303422Y378469D01*
X303289Y377869D01*
X306089D01*
G01X334717Y378669D02*
X335117Y378202D01*
X335651Y377936D01*
X336251Y377869D01*
X336784Y377936D01*
X337317Y378269D01*
X337651Y378669D01*
X337717Y379069D01*
X337584Y379536D01*
X337117Y379869D01*
X336651Y380002D01*
X336051D01*
G01X336651D02*
X337051Y380202D01*
X337384Y380536D01*
X337517Y380936D01*
X337384Y381336D01*
X337051Y381669D01*
X336451Y381869D01*
X335851Y381802D01*
X335251Y381536D01*
G01X368479Y377869D02*
Y381869D01*
X366012Y379002D01*
X369346D01*
G01X397707Y378469D02*
X398107Y378136D01*
X398574Y377936D01*
X399174Y377869D01*
X399774Y378002D01*
X400241Y378269D01*
X400574Y378736D01*
X400641Y379269D01*
X400507Y379802D01*
X400174Y380136D01*
X399707Y380402D01*
X399241Y380469D01*
X398774Y380402D01*
X398174Y380136D01*
X398374Y381869D01*
X400174D01*
G01X429403Y379536D02*
X429870Y380002D01*
X430270Y380269D01*
X430803Y380402D01*
X431270Y380269D01*
X431603Y380002D01*
X431870Y379602D01*
X431937Y379136D01*
X431870Y378736D01*
X431603Y378336D01*
X431203Y378002D01*
X430737Y377869D01*
X430203Y378002D01*
X429737Y378402D01*
X429470Y379002D01*
X429403Y379669D01*
X429537Y380536D01*
X429737Y381002D01*
X430070Y381469D01*
X430537Y381802D01*
X431003Y381869D01*
X431470Y381736D01*
X431803Y381402D01*
G01X490980Y217442D02*
Y209642D01*
X478380D01*
Y217442D01*
X490980D01*
G01X483480Y211842D02*
X482980Y211342D01*
X482380Y211142D01*
X481680Y211042D01*
X480880Y211142D01*
X480280Y211642D01*
X480080Y212142D01*
X480180Y212642D01*
X480480Y213042D01*
X482180Y213842D01*
X482980Y214442D01*
X483480Y215242D01*
X483580Y216042D01*
X480080D01*
G01X487480Y211042D02*
X488080Y211142D01*
X488580Y211642D01*
X488980Y212142D01*
X489180Y212742D01*
X489280Y213542D01*
X489180Y214242D01*
X488980Y214942D01*
X488580Y215442D01*
X488080Y215842D01*
X487480Y216042D01*
X486780Y215842D01*
X486280Y215442D01*
X485980Y214942D01*
X485680Y214242D01*
X485580Y213542D01*
X485680Y212742D01*
X485980Y212142D01*
X486280Y211642D01*
X486780Y211142D01*
X487480Y211042D01*
G01X604489Y40629D02*
Y48429D01*
X617089D01*
Y40629D01*
X604489D01*
G01X607989Y47029D02*
X607389Y46929D01*
X606889Y46429D01*
X606489Y45929D01*
X606289Y45329D01*
X606189Y44529D01*
X606289Y43829D01*
X606489Y43129D01*
X606889Y42629D01*
X607389Y42229D01*
X607989Y42029D01*
X608689Y42229D01*
X609189Y42629D01*
X609489Y43129D01*
X609789Y43829D01*
X609889Y44529D01*
X609789Y45329D01*
X609489Y45929D01*
X609189Y46429D01*
X608689Y46929D01*
X607989Y47029D01*
G01X614589Y42029D02*
Y47029D01*
X611489Y43429D01*
X615689D01*
M02*
